(kicad_sch
	(version 20250114)
	(generator "eeschema")
	(generator_version "9.0")
	(paper "A3")
	(title_block
		(title "OCuLink to PCIe adapter")
		(date "2025-06-18")
		(rev "1.0.0")
		(company "Antmicro Ltd")
		(comment 1 "www.antmicro.com")
	)
	(text "PCIe x16 connector"
		(exclude_from_sim no)
		(at 206.248 62.738 0)
		(effects
			(font
				(size 2 2)
				(thickness 0.4)
				(bold yes)
			)
			(justify left bottom)
		)
	)
	(junction
		(at 175.26 93.98)
		(diameter 0)
		(color 0 0 0 0)
	)
	(junction
		(at 147.32 173.99)
		(diameter 0)
		(color 0 0 0 0)
	)
	(junction
		(at 175.26 130.81)
		(diameter 0)
		(color 0 0 0 0)
	)
	(junction
		(at 147.32 118.11)
		(diameter 0)
		(color 0 0 0 0)
	)
	(junction
		(at 264.16 130.81)
		(diameter 0)
		(color 0 0 0 0)
	)
	(junction
		(at 147.32 189.23)
		(diameter 0)
		(color 0 0 0 0)
	)
	(junction
		(at 292.1 209.55)
		(diameter 0)
		(color 0 0 0 0)
	)
	(junction
		(at 189.23 123.19)
		(diameter 0)
		(color 0 0 0 0)
	)
	(junction
		(at 292.1 120.65)
		(diameter 0)
		(color 0 0 0 0)
	)
	(junction
		(at 147.32 199.39)
		(diameter 0)
		(color 0 0 0 0)
	)
	(junction
		(at 264.16 107.95)
		(diameter 0)
		(color 0 0 0 0)
	)
	(junction
		(at 264.16 128.27)
		(diameter 0)
		(color 0 0 0 0)
	)
	(junction
		(at 292.1 146.05)
		(diameter 0)
		(color 0 0 0 0)
	)
	(junction
		(at 175.26 186.69)
		(diameter 0)
		(color 0 0 0 0)
	)
	(junction
		(at 189.23 116.84)
		(diameter 0)
		(color 0 0 0 0)
	)
	(junction
		(at 292.1 113.03)
		(diameter 0)
		(color 0 0 0 0)
	)
	(junction
		(at 175.26 146.05)
		(diameter 0)
		(color 0 0 0 0)
	)
	(junction
		(at 175.26 158.75)
		(diameter 0)
		(color 0 0 0 0)
	)
	(junction
		(at 264.16 168.91)
		(diameter 0)
		(color 0 0 0 0)
	)
	(junction
		(at 292.1 184.15)
		(diameter 0)
		(color 0 0 0 0)
	)
	(junction
		(at 147.32 146.05)
		(diameter 0)
		(color 0 0 0 0)
	)
	(junction
		(at 264.16 161.29)
		(diameter 0)
		(color 0 0 0 0)
	)
	(junction
		(at 292.1 194.31)
		(diameter 0)
		(color 0 0 0 0)
	)
	(junction
		(at 175.26 194.31)
		(diameter 0)
		(color 0 0 0 0)
	)
	(junction
		(at 175.26 151.13)
		(diameter 0)
		(color 0 0 0 0)
	)
	(junction
		(at 147.32 133.35)
		(diameter 0)
		(color 0 0 0 0)
	)
	(junction
		(at 175.26 105.41)
		(diameter 0)
		(color 0 0 0 0)
	)
	(junction
		(at 264.16 181.61)
		(diameter 0)
		(color 0 0 0 0)
	)
	(junction
		(at 175.26 168.91)
		(diameter 0)
		(color 0 0 0 0)
	)
	(junction
		(at 147.32 191.77)
		(diameter 0)
		(color 0 0 0 0)
	)
	(junction
		(at 292.1 133.35)
		(diameter 0)
		(color 0 0 0 0)
	)
	(junction
		(at 292.1 163.83)
		(diameter 0)
		(color 0 0 0 0)
	)
	(junction
		(at 292.1 125.73)
		(diameter 0)
		(color 0 0 0 0)
	)
	(junction
		(at 264.16 171.45)
		(diameter 0)
		(color 0 0 0 0)
	)
	(junction
		(at 264.16 138.43)
		(diameter 0)
		(color 0 0 0 0)
	)
	(junction
		(at 264.16 140.97)
		(diameter 0)
		(color 0 0 0 0)
	)
	(junction
		(at 292.1 176.53)
		(diameter 0)
		(color 0 0 0 0)
	)
	(junction
		(at 175.26 161.29)
		(diameter 0)
		(color 0 0 0 0)
	)
	(junction
		(at 175.26 171.45)
		(diameter 0)
		(color 0 0 0 0)
	)
	(junction
		(at 264.16 199.39)
		(diameter 0)
		(color 0 0 0 0)
	)
	(junction
		(at 113.03 74.93)
		(diameter 0)
		(color 0 0 0 0)
	)
	(junction
		(at 120.65 120.65)
		(diameter 0)
		(color 0 0 0 0)
	)
	(junction
		(at 147.32 105.41)
		(diameter 0)
		(color 0 0 0 0)
	)
	(junction
		(at 179.07 93.98)
		(diameter 0)
		(color 0 0 0 0)
	)
	(junction
		(at 147.32 156.21)
		(diameter 0)
		(color 0 0 0 0)
	)
	(junction
		(at 292.1 196.85)
		(diameter 0)
		(color 0 0 0 0)
	)
	(junction
		(at 147.32 201.93)
		(diameter 0)
		(color 0 0 0 0)
	)
	(junction
		(at 175.26 204.47)
		(diameter 0)
		(color 0 0 0 0)
	)
	(junction
		(at 175.26 138.43)
		(diameter 0)
		(color 0 0 0 0)
	)
	(junction
		(at 264.16 209.55)
		(diameter 0)
		(color 0 0 0 0)
	)
	(junction
		(at 147.32 153.67)
		(diameter 0)
		(color 0 0 0 0)
	)
	(junction
		(at 292.1 135.89)
		(diameter 0)
		(color 0 0 0 0)
	)
	(junction
		(at 120.65 93.98)
		(diameter 0)
		(color 0 0 0 0)
	)
	(junction
		(at 292.1 173.99)
		(diameter 0)
		(color 0 0 0 0)
	)
	(junction
		(at 264.16 158.75)
		(diameter 0)
		(color 0 0 0 0)
	)
	(junction
		(at 264.16 189.23)
		(diameter 0)
		(color 0 0 0 0)
	)
	(junction
		(at 264.16 148.59)
		(diameter 0)
		(color 0 0 0 0)
	)
	(junction
		(at 147.32 181.61)
		(diameter 0)
		(color 0 0 0 0)
	)
	(junction
		(at 175.26 179.07)
		(diameter 0)
		(color 0 0 0 0)
	)
	(junction
		(at 292.1 186.69)
		(diameter 0)
		(color 0 0 0 0)
	)
	(junction
		(at 292.1 156.21)
		(diameter 0)
		(color 0 0 0 0)
	)
	(junction
		(at 264.16 191.77)
		(diameter 0)
		(color 0 0 0 0)
	)
	(junction
		(at 147.32 163.83)
		(diameter 0)
		(color 0 0 0 0)
	)
	(junction
		(at 264.16 115.57)
		(diameter 0)
		(color 0 0 0 0)
	)
	(junction
		(at 292.1 166.37)
		(diameter 0)
		(color 0 0 0 0)
	)
	(junction
		(at 264.16 179.07)
		(diameter 0)
		(color 0 0 0 0)
	)
	(junction
		(at 292.1 110.49)
		(diameter 0)
		(color 0 0 0 0)
	)
	(junction
		(at 292.1 204.47)
		(diameter 0)
		(color 0 0 0 0)
	)
	(junction
		(at 147.32 102.87)
		(diameter 0)
		(color 0 0 0 0)
	)
	(junction
		(at 292.1 153.67)
		(diameter 0)
		(color 0 0 0 0)
	)
	(junction
		(at 292.1 143.51)
		(diameter 0)
		(color 0 0 0 0)
	)
	(junction
		(at 147.32 166.37)
		(diameter 0)
		(color 0 0 0 0)
	)
	(junction
		(at 175.26 196.85)
		(diameter 0)
		(color 0 0 0 0)
	)
	(junction
		(at 147.32 140.97)
		(diameter 0)
		(color 0 0 0 0)
	)
	(junction
		(at 264.16 151.13)
		(diameter 0)
		(color 0 0 0 0)
	)
	(junction
		(at 147.32 93.98)
		(diameter 0)
		(color 0 0 0 0)
	)
	(junction
		(at 264.16 120.65)
		(diameter 0)
		(color 0 0 0 0)
	)
	(no_connect
		(at 266.7 143.51)
	)
	(no_connect
		(at 266.7 204.47)
	)
	(no_connect
		(at 172.72 120.65)
	)
	(no_connect
		(at 266.7 173.99)
	)
	(no_connect
		(at 289.56 105.41)
	)
	(no_connect
		(at 266.7 156.21)
	)
	(no_connect
		(at 266.7 113.03)
	)
	(no_connect
		(at 289.56 199.39)
	)
	(no_connect
		(at 149.86 204.47)
	)
	(no_connect
		(at 289.56 148.59)
	)
	(no_connect
		(at 266.7 146.05)
	)
	(no_connect
		(at 289.56 181.61)
	)
	(no_connect
		(at 266.7 184.15)
	)
	(no_connect
		(at 289.56 140.97)
	)
	(no_connect
		(at 149.86 123.19)
	)
	(no_connect
		(at 266.7 176.53)
	)
	(no_connect
		(at 172.72 201.93)
	)
	(no_connect
		(at 289.56 191.77)
	)
	(no_connect
		(at 172.72 184.15)
	)
	(no_connect
		(at 172.72 191.77)
	)
	(no_connect
		(at 149.86 186.69)
	)
	(no_connect
		(at 266.7 201.93)
	)
	(no_connect
		(at 266.7 153.67)
	)
	(no_connect
		(at 172.72 181.61)
	)
	(no_connect
		(at 149.86 179.07)
	)
	(no_connect
		(at 266.7 133.35)
	)
	(no_connect
		(at 266.7 123.19)
	)
	(no_connect
		(at 289.56 201.93)
	)
	(no_connect
		(at 266.7 186.69)
	)
	(no_connect
		(at 289.56 171.45)
	)
	(no_connect
		(at 289.56 189.23)
	)
	(no_connect
		(at 172.72 102.87)
	)
	(no_connect
		(at 149.86 130.81)
	)
	(no_connect
		(at 172.72 148.59)
	)
	(no_connect
		(at 289.56 123.19)
	)
	(no_connect
		(at 172.72 113.03)
	)
	(no_connect
		(at 289.56 128.27)
	)
	(no_connect
		(at 149.86 184.15)
	)
	(no_connect
		(at 266.7 118.11)
	)
	(no_connect
		(at 266.7 163.83)
	)
	(no_connect
		(at 149.86 176.53)
	)
	(no_connect
		(at 289.56 107.95)
	)
	(no_connect
		(at 289.56 179.07)
	)
	(no_connect
		(at 172.72 199.39)
	)
	(no_connect
		(at 289.56 158.75)
	)
	(no_connect
		(at 266.7 166.37)
	)
	(no_connect
		(at 172.72 189.23)
	)
	(no_connect
		(at 266.7 125.73)
	)
	(no_connect
		(at 289.56 151.13)
	)
	(no_connect
		(at 289.56 168.91)
	)
	(no_connect
		(at 266.7 196.85)
	)
	(no_connect
		(at 149.86 143.51)
	)
	(no_connect
		(at 172.72 118.11)
	)
	(no_connect
		(at 266.7 194.31)
	)
	(no_connect
		(at 149.86 194.31)
	)
	(no_connect
		(at 149.86 196.85)
	)
	(no_connect
		(at 266.7 102.87)
	)
	(no_connect
		(at 172.72 115.57)
	)
	(no_connect
		(at 289.56 138.43)
	)
	(no_connect
		(at 266.7 110.49)
	)
	(no_connect
		(at 266.7 135.89)
	)
	(no_connect
		(at 289.56 118.11)
	)
	(no_connect
		(at 289.56 130.81)
	)
	(no_connect
		(at 289.56 115.57)
	)
	(no_connect
		(at 289.56 161.29)
	)
	(bus_entry
		(at 113.03 149.86)
		(size 1.27 1.27)
		(stroke
			(width 0)
			(type default)
		)
	)
	(bus_entry
		(at 113.03 170.18)
		(size 1.27 1.27)
		(stroke
			(width 0)
			(type default)
		)
	)
	(bus_entry
		(at 113.03 137.16)
		(size 1.27 1.27)
		(stroke
			(width 0)
			(type default)
		)
	)
	(bus_entry
		(at 92.71 115.57)
		(size -1.27 -1.27)
		(stroke
			(width 0)
			(type default)
		)
	)
	(bus_entry
		(at 113.03 167.64)
		(size 1.27 1.27)
		(stroke
			(width 0)
			(type default)
		)
	)
	(bus_entry
		(at 205.74 152.4)
		(size -1.27 1.27)
		(stroke
			(width 0)
			(type default)
		)
	)
	(bus_entry
		(at 231.14 135.89)
		(size 1.27 -1.27)
		(stroke
			(width 0)
			(type default)
		)
	)
	(bus_entry
		(at 205.74 165.1)
		(size -1.27 1.27)
		(stroke
			(width 0)
			(type default)
		)
	)
	(bus_entry
		(at 113.03 160.02)
		(size 1.27 1.27)
		(stroke
			(width 0)
			(type default)
		)
	)
	(bus_entry
		(at 205.74 175.26)
		(size -1.27 1.27)
		(stroke
			(width 0)
			(type default)
		)
	)
	(bus_entry
		(at 113.03 157.48)
		(size 1.27 1.27)
		(stroke
			(width 0)
			(type default)
		)
	)
	(bus_entry
		(at 231.14 133.35)
		(size 1.27 -1.27)
		(stroke
			(width 0)
			(type default)
		)
	)
	(bus_entry
		(at 205.74 162.56)
		(size -1.27 1.27)
		(stroke
			(width 0)
			(type default)
		)
	)
	(bus_entry
		(at 113.03 134.62)
		(size 1.27 1.27)
		(stroke
			(width 0)
			(type default)
		)
	)
	(bus_entry
		(at 92.71 113.03)
		(size -1.27 -1.27)
		(stroke
			(width 0)
			(type default)
		)
	)
	(bus_entry
		(at 205.74 142.24)
		(size -1.27 1.27)
		(stroke
			(width 0)
			(type default)
		)
	)
	(bus_entry
		(at 113.03 147.32)
		(size 1.27 1.27)
		(stroke
			(width 0)
			(type default)
		)
	)
	(bus_entry
		(at 205.74 154.94)
		(size -1.27 1.27)
		(stroke
			(width 0)
			(type default)
		)
	)
	(bus_entry
		(at 205.74 172.72)
		(size -1.27 1.27)
		(stroke
			(width 0)
			(type default)
		)
	)
	(bus_entry
		(at 205.74 139.7)
		(size -1.27 1.27)
		(stroke
			(width 0)
			(type default)
		)
	)
	(wire
		(pts
			(xy 120.65 91.44) (xy 120.65 93.98)
		)
		(stroke
			(width 0)
			(type default)
		)
	)
	(wire
		(pts
			(xy 264.16 148.59) (xy 266.7 148.59)
		)
		(stroke
			(width 0)
			(type default)
		)
	)
	(bus
		(pts
			(xy 232.41 132.08) (xy 232.41 129.54)
		)
		(stroke
			(width 0)
			(type default)
		)
	)
	(wire
		(pts
			(xy 147.32 166.37) (xy 149.86 166.37)
		)
		(stroke
			(width 0)
			(type default)
		)
	)
	(wire
		(pts
			(xy 172.72 146.05) (xy 175.26 146.05)
		)
		(stroke
			(width 0)
			(type default)
		)
	)
	(wire
		(pts
			(xy 114.3 138.43) (xy 149.86 138.43)
		)
		(stroke
			(width 0)
			(type default)
		)
	)
	(wire
		(pts
			(xy 172.72 156.21) (xy 204.47 156.21)
		)
		(stroke
			(width 0)
			(type default)
		)
	)
	(wire
		(pts
			(xy 114.3 171.45) (xy 149.86 171.45)
		)
		(stroke
			(width 0)
			(type default)
		)
	)
	(wire
		(pts
			(xy 172.72 194.31) (xy 175.26 194.31)
		)
		(stroke
			(width 0)
			(type default)
		)
	)
	(bus
		(pts
			(xy 205.74 154.94) (xy 205.74 152.4)
		)
		(stroke
			(width 0)
			(type default)
		)
	)
	(wire
		(pts
			(xy 172.72 123.19) (xy 189.23 123.19)
		)
		(stroke
			(width 0)
			(type default)
		)
	)
	(wire
		(pts
			(xy 172.72 166.37) (xy 204.47 166.37)
		)
		(stroke
			(width 0)
			(type default)
		)
	)
	(wire
		(pts
			(xy 172.72 158.75) (xy 175.26 158.75)
		)
		(stroke
			(width 0)
			(type default)
		)
	)
	(wire
		(pts
			(xy 147.32 91.44) (xy 147.32 93.98)
		)
		(stroke
			(width 0)
			(type default)
		)
	)
	(wire
		(pts
			(xy 149.86 115.57) (xy 92.71 115.57)
		)
		(stroke
			(width 0)
			(type default)
		)
	)
	(wire
		(pts
			(xy 138.43 93.98) (xy 147.32 93.98)
		)
		(stroke
			(width 0)
			(type default)
		)
	)
	(wire
		(pts
			(xy 172.72 153.67) (xy 204.47 153.67)
		)
		(stroke
			(width 0)
			(type default)
		)
	)
	(bus
		(pts
			(xy 113.03 149.86) (xy 113.03 157.48)
		)
		(stroke
			(width 0)
			(type default)
		)
	)
	(wire
		(pts
			(xy 138.43 101.6) (xy 138.43 104.14)
		)
		(stroke
			(width 0)
			(type default)
		)
	)
	(wire
		(pts
			(xy 175.26 196.85) (xy 175.26 204.47)
		)
		(stroke
			(width 0)
			(type default)
		)
	)
	(bus
		(pts
			(xy 205.74 139.7) (xy 205.74 74.93)
		)
		(stroke
			(width 0)
			(type default)
		)
	)
	(wire
		(pts
			(xy 147.32 199.39) (xy 147.32 201.93)
		)
		(stroke
			(width 0)
			(type default)
		)
	)
	(wire
		(pts
			(xy 172.72 176.53) (xy 204.47 176.53)
		)
		(stroke
			(width 0)
			(type default)
		)
	)
	(wire
		(pts
			(xy 189.23 116.84) (xy 195.58 116.84)
		)
		(stroke
			(width 0)
			(type default)
		)
	)
	(wire
		(pts
			(xy 264.16 105.41) (xy 266.7 105.41)
		)
		(stroke
			(width 0)
			(type default)
		)
	)
	(bus
		(pts
			(xy 205.74 142.24) (xy 205.74 139.7)
		)
		(stroke
			(width 0)
			(type default)
		)
	)
	(wire
		(pts
			(xy 292.1 113.03) (xy 292.1 120.65)
		)
		(stroke
			(width 0)
			(type default)
		)
	)
	(wire
		(pts
			(xy 189.23 114.3) (xy 189.23 116.84)
		)
		(stroke
			(width 0)
			(type default)
		)
	)
	(wire
		(pts
			(xy 175.26 204.47) (xy 175.26 208.28)
		)
		(stroke
			(width 0)
			(type default)
		)
	)
	(wire
		(pts
			(xy 292.1 204.47) (xy 292.1 209.55)
		)
		(stroke
			(width 0)
			(type default)
		)
	)
	(wire
		(pts
			(xy 264.16 179.07) (xy 266.7 179.07)
		)
		(stroke
			(width 0)
			(type default)
		)
	)
	(wire
		(pts
			(xy 147.32 153.67) (xy 147.32 156.21)
		)
		(stroke
			(width 0)
			(type default)
		)
	)
	(wire
		(pts
			(xy 195.58 124.46) (xy 195.58 127)
		)
		(stroke
			(width 0)
			(type default)
		)
	)
	(wire
		(pts
			(xy 292.1 143.51) (xy 292.1 146.05)
		)
		(stroke
			(width 0)
			(type default)
		)
	)
	(wire
		(pts
			(xy 289.56 156.21) (xy 292.1 156.21)
		)
		(stroke
			(width 0)
			(type default)
		)
	)
	(wire
		(pts
			(xy 187.96 101.6) (xy 187.96 104.14)
		)
		(stroke
			(width 0)
			(type default)
		)
	)
	(wire
		(pts
			(xy 289.56 110.49) (xy 292.1 110.49)
		)
		(stroke
			(width 0)
			(type default)
		)
	)
	(bus
		(pts
			(xy 233.68 128.27) (xy 236.22 128.27)
		)
		(stroke
			(width 0)
			(type default)
		)
	)
	(bus
		(pts
			(xy 205.74 172.72) (xy 205.74 165.1)
		)
		(stroke
			(width 0)
			(type default)
		)
	)
	(wire
		(pts
			(xy 147.32 153.67) (xy 149.86 153.67)
		)
		(stroke
			(width 0)
			(type default)
		)
	)
	(wire
		(pts
			(xy 147.32 156.21) (xy 149.86 156.21)
		)
		(stroke
			(width 0)
			(type default)
		)
	)
	(wire
		(pts
			(xy 289.56 184.15) (xy 292.1 184.15)
		)
		(stroke
			(width 0)
			(type default)
		)
	)
	(wire
		(pts
			(xy 289.56 120.65) (xy 292.1 120.65)
		)
		(stroke
			(width 0)
			(type default)
		)
	)
	(wire
		(pts
			(xy 175.26 186.69) (xy 175.26 194.31)
		)
		(stroke
			(width 0)
			(type default)
		)
	)
	(wire
		(pts
			(xy 172.72 163.83) (xy 204.47 163.83)
		)
		(stroke
			(width 0)
			(type default)
		)
	)
	(wire
		(pts
			(xy 264.16 107.95) (xy 266.7 107.95)
		)
		(stroke
			(width 0)
			(type default)
		)
	)
	(bus
		(pts
			(xy 105.41 74.93) (xy 113.03 74.93)
		)
		(stroke
			(width 0)
			(type default)
		)
	)
	(wire
		(pts
			(xy 264.16 161.29) (xy 264.16 168.91)
		)
		(stroke
			(width 0)
			(type default)
		)
	)
	(wire
		(pts
			(xy 147.32 163.83) (xy 149.86 163.83)
		)
		(stroke
			(width 0)
			(type default)
		)
	)
	(wire
		(pts
			(xy 147.32 118.11) (xy 147.32 133.35)
		)
		(stroke
			(width 0)
			(type default)
		)
	)
	(wire
		(pts
			(xy 149.86 110.49) (xy 147.32 110.49)
		)
		(stroke
			(width 0)
			(type default)
		)
	)
	(wire
		(pts
			(xy 172.72 130.81) (xy 175.26 130.81)
		)
		(stroke
			(width 0)
			(type default)
		)
	)
	(bus
		(pts
			(xy 113.03 160.02) (xy 113.03 157.48)
		)
		(stroke
			(width 0)
			(type default)
		)
	)
	(wire
		(pts
			(xy 147.32 189.23) (xy 149.86 189.23)
		)
		(stroke
			(width 0)
			(type default)
		)
	)
	(wire
		(pts
			(xy 289.56 113.03) (xy 292.1 113.03)
		)
		(stroke
			(width 0)
			(type default)
		)
	)
	(wire
		(pts
			(xy 147.32 173.99) (xy 147.32 181.61)
		)
		(stroke
			(width 0)
			(type default)
		)
	)
	(wire
		(pts
			(xy 264.16 189.23) (xy 264.16 191.77)
		)
		(stroke
			(width 0)
			(type default)
		)
	)
	(wire
		(pts
			(xy 130.81 125.73) (xy 149.86 125.73)
		)
		(stroke
			(width 0)
			(type default)
		)
	)
	(wire
		(pts
			(xy 147.32 181.61) (xy 147.32 189.23)
		)
		(stroke
			(width 0)
			(type default)
		)
	)
	(wire
		(pts
			(xy 264.16 138.43) (xy 266.7 138.43)
		)
		(stroke
			(width 0)
			(type default)
		)
	)
	(wire
		(pts
			(xy 264.16 189.23) (xy 266.7 189.23)
		)
		(stroke
			(width 0)
			(type default)
		)
	)
	(wire
		(pts
			(xy 147.32 173.99) (xy 149.86 173.99)
		)
		(stroke
			(width 0)
			(type default)
		)
	)
	(wire
		(pts
			(xy 264.16 181.61) (xy 266.7 181.61)
		)
		(stroke
			(width 0)
			(type default)
		)
	)
	(wire
		(pts
			(xy 189.23 116.84) (xy 189.23 123.19)
		)
		(stroke
			(width 0)
			(type default)
		)
	)
	(wire
		(pts
			(xy 264.16 140.97) (xy 266.7 140.97)
		)
		(stroke
			(width 0)
			(type default)
		)
	)
	(wire
		(pts
			(xy 264.16 158.75) (xy 264.16 161.29)
		)
		(stroke
			(width 0)
			(type default)
		)
	)
	(wire
		(pts
			(xy 264.16 191.77) (xy 266.7 191.77)
		)
		(stroke
			(width 0)
			(type default)
		)
	)
	(wire
		(pts
			(xy 172.72 105.41) (xy 175.26 105.41)
		)
		(stroke
			(width 0)
			(type default)
		)
	)
	(wire
		(pts
			(xy 292.1 209.55) (xy 292.1 210.82)
		)
		(stroke
			(width 0)
			(type default)
		)
	)
	(wire
		(pts
			(xy 264.16 151.13) (xy 264.16 158.75)
		)
		(stroke
			(width 0)
			(type default)
		)
	)
	(wire
		(pts
			(xy 175.26 105.41) (xy 175.26 107.95)
		)
		(stroke
			(width 0)
			(type default)
		)
	)
	(wire
		(pts
			(xy 114.3 135.89) (xy 149.86 135.89)
		)
		(stroke
			(width 0)
			(type default)
		)
	)
	(wire
		(pts
			(xy 292.1 184.15) (xy 292.1 186.69)
		)
		(stroke
			(width 0)
			(type default)
		)
	)
	(wire
		(pts
			(xy 120.65 120.65) (xy 120.65 125.73)
		)
		(stroke
			(width 0)
			(type default)
		)
	)
	(wire
		(pts
			(xy 264.16 148.59) (xy 264.16 151.13)
		)
		(stroke
			(width 0)
			(type default)
		)
	)
	(wire
		(pts
			(xy 264.16 199.39) (xy 266.7 199.39)
		)
		(stroke
			(width 0)
			(type default)
		)
	)
	(bus
		(pts
			(xy 91.44 109.22) (xy 90.17 107.95)
		)
		(stroke
			(width 0)
			(type default)
		)
	)
	(wire
		(pts
			(xy 175.26 171.45) (xy 175.26 179.07)
		)
		(stroke
			(width 0)
			(type default)
		)
	)
	(wire
		(pts
			(xy 127 101.6) (xy 127 104.14)
		)
		(stroke
			(width 0)
			(type default)
		)
	)
	(wire
		(pts
			(xy 264.16 115.57) (xy 266.7 115.57)
		)
		(stroke
			(width 0)
			(type default)
		)
	)
	(wire
		(pts
			(xy 114.3 168.91) (xy 149.86 168.91)
		)
		(stroke
			(width 0)
			(type default)
		)
	)
	(bus
		(pts
			(xy 113.03 167.64) (xy 113.03 170.18)
		)
		(stroke
			(width 0)
			(type default)
		)
	)
	(wire
		(pts
			(xy 127 96.52) (xy 127 93.98)
		)
		(stroke
			(width 0)
			(type default)
		)
	)
	(bus
		(pts
			(xy 205.74 165.1) (xy 205.74 162.56)
		)
		(stroke
			(width 0)
			(type default)
		)
	)
	(bus
		(pts
			(xy 113.03 160.02) (xy 113.03 167.64)
		)
		(stroke
			(width 0)
			(type default)
		)
	)
	(wire
		(pts
			(xy 289.56 143.51) (xy 292.1 143.51)
		)
		(stroke
			(width 0)
			(type default)
		)
	)
	(wire
		(pts
			(xy 147.32 156.21) (xy 147.32 163.83)
		)
		(stroke
			(width 0)
			(type default)
		)
	)
	(wire
		(pts
			(xy 289.56 176.53) (xy 292.1 176.53)
		)
		(stroke
			(width 0)
			(type default)
		)
	)
	(wire
		(pts
			(xy 175.26 194.31) (xy 175.26 196.85)
		)
		(stroke
			(width 0)
			(type default)
		)
	)
	(wire
		(pts
			(xy 172.72 171.45) (xy 175.26 171.45)
		)
		(stroke
			(width 0)
			(type default)
		)
	)
	(bus
		(pts
			(xy 232.41 129.54) (xy 233.68 128.27)
		)
		(stroke
			(width 0)
			(type default)
		)
	)
	(wire
		(pts
			(xy 289.56 186.69) (xy 292.1 186.69)
		)
		(stroke
			(width 0)
			(type default)
		)
	)
	(wire
		(pts
			(xy 138.43 96.52) (xy 138.43 93.98)
		)
		(stroke
			(width 0)
			(type default)
		)
	)
	(wire
		(pts
			(xy 147.32 133.35) (xy 149.86 133.35)
		)
		(stroke
			(width 0)
			(type default)
		)
	)
	(wire
		(pts
			(xy 292.1 135.89) (xy 292.1 143.51)
		)
		(stroke
			(width 0)
			(type default)
		)
	)
	(bus
		(pts
			(xy 113.03 149.86) (xy 113.03 147.32)
		)
		(stroke
			(width 0)
			(type default)
		)
	)
	(wire
		(pts
			(xy 172.72 143.51) (xy 204.47 143.51)
		)
		(stroke
			(width 0)
			(type default)
		)
	)
	(wire
		(pts
			(xy 289.56 153.67) (xy 292.1 153.67)
		)
		(stroke
			(width 0)
			(type default)
		)
	)
	(wire
		(pts
			(xy 114.3 161.29) (xy 149.86 161.29)
		)
		(stroke
			(width 0)
			(type default)
		)
	)
	(wire
		(pts
			(xy 289.56 102.87) (xy 292.1 102.87)
		)
		(stroke
			(width 0)
			(type default)
		)
	)
	(wire
		(pts
			(xy 292.1 156.21) (xy 292.1 163.83)
		)
		(stroke
			(width 0)
			(type default)
		)
	)
	(wire
		(pts
			(xy 264.16 168.91) (xy 266.7 168.91)
		)
		(stroke
			(width 0)
			(type default)
		)
	)
	(bus
		(pts
			(xy 113.03 134.62) (xy 113.03 137.16)
		)
		(stroke
			(width 0)
			(type default)
		)
	)
	(wire
		(pts
			(xy 175.26 161.29) (xy 175.26 168.91)
		)
		(stroke
			(width 0)
			(type default)
		)
	)
	(wire
		(pts
			(xy 264.16 179.07) (xy 264.16 181.61)
		)
		(stroke
			(width 0)
			(type default)
		)
	)
	(wire
		(pts
			(xy 292.1 125.73) (xy 292.1 133.35)
		)
		(stroke
			(width 0)
			(type default)
		)
	)
	(wire
		(pts
			(xy 264.16 181.61) (xy 264.16 189.23)
		)
		(stroke
			(width 0)
			(type default)
		)
	)
	(bus
		(pts
			(xy 232.41 134.62) (xy 232.41 132.08)
		)
		(stroke
			(width 0)
			(type default)
		)
	)
	(wire
		(pts
			(xy 147.32 181.61) (xy 149.86 181.61)
		)
		(stroke
			(width 0)
			(type default)
		)
	)
	(bus
		(pts
			(xy 113.03 74.93) (xy 113.03 134.62)
		)
		(stroke
			(width 0)
			(type default)
		)
	)
	(wire
		(pts
			(xy 187.96 93.98) (xy 179.07 93.98)
		)
		(stroke
			(width 0)
			(type default)
		)
	)
	(wire
		(pts
			(xy 292.1 153.67) (xy 292.1 156.21)
		)
		(stroke
			(width 0)
			(type default)
		)
	)
	(wire
		(pts
			(xy 264.16 120.65) (xy 264.16 128.27)
		)
		(stroke
			(width 0)
			(type default)
		)
	)
	(wire
		(pts
			(xy 172.72 173.99) (xy 204.47 173.99)
		)
		(stroke
			(width 0)
			(type default)
		)
	)
	(wire
		(pts
			(xy 175.26 91.44) (xy 175.26 93.98)
		)
		(stroke
			(width 0)
			(type default)
		)
	)
	(wire
		(pts
			(xy 264.16 171.45) (xy 264.16 179.07)
		)
		(stroke
			(width 0)
			(type default)
		)
	)
	(wire
		(pts
			(xy 264.16 171.45) (xy 266.7 171.45)
		)
		(stroke
			(width 0)
			(type default)
		)
	)
	(wire
		(pts
			(xy 292.1 196.85) (xy 292.1 204.47)
		)
		(stroke
			(width 0)
			(type default)
		)
	)
	(bus
		(pts
			(xy 90.17 107.95) (xy 87.63 107.95)
		)
		(stroke
			(width 0)
			(type default)
		)
	)
	(wire
		(pts
			(xy 175.26 110.49) (xy 175.26 130.81)
		)
		(stroke
			(width 0)
			(type default)
		)
	)
	(wire
		(pts
			(xy 114.3 148.59) (xy 149.86 148.59)
		)
		(stroke
			(width 0)
			(type default)
		)
	)
	(bus
		(pts
			(xy 205.74 152.4) (xy 205.74 142.24)
		)
		(stroke
			(width 0)
			(type default)
		)
	)
	(wire
		(pts
			(xy 264.16 191.77) (xy 264.16 199.39)
		)
		(stroke
			(width 0)
			(type default)
		)
	)
	(wire
		(pts
			(xy 264.16 105.41) (xy 264.16 107.95)
		)
		(stroke
			(width 0)
			(type default)
		)
	)
	(wire
		(pts
			(xy 120.65 120.65) (xy 149.86 120.65)
		)
		(stroke
			(width 0)
			(type default)
		)
	)
	(wire
		(pts
			(xy 114.3 158.75) (xy 149.86 158.75)
		)
		(stroke
			(width 0)
			(type default)
		)
	)
	(wire
		(pts
			(xy 289.56 135.89) (xy 292.1 135.89)
		)
		(stroke
			(width 0)
			(type default)
		)
	)
	(wire
		(pts
			(xy 147.32 191.77) (xy 147.32 199.39)
		)
		(stroke
			(width 0)
			(type default)
		)
	)
	(bus
		(pts
			(xy 113.03 137.16) (xy 113.03 147.32)
		)
		(stroke
			(width 0)
			(type default)
		)
	)
	(wire
		(pts
			(xy 289.56 196.85) (xy 292.1 196.85)
		)
		(stroke
			(width 0)
			(type default)
		)
	)
	(wire
		(pts
			(xy 292.1 186.69) (xy 292.1 194.31)
		)
		(stroke
			(width 0)
			(type default)
		)
	)
	(wire
		(pts
			(xy 292.1 146.05) (xy 292.1 153.67)
		)
		(stroke
			(width 0)
			(type default)
		)
	)
	(wire
		(pts
			(xy 292.1 120.65) (xy 292.1 125.73)
		)
		(stroke
			(width 0)
			(type default)
		)
	)
	(wire
		(pts
			(xy 147.32 93.98) (xy 147.32 102.87)
		)
		(stroke
			(width 0)
			(type default)
		)
	)
	(wire
		(pts
			(xy 114.3 151.13) (xy 149.86 151.13)
		)
		(stroke
			(width 0)
			(type default)
		)
	)
	(wire
		(pts
			(xy 172.72 161.29) (xy 175.26 161.29)
		)
		(stroke
			(width 0)
			(type default)
		)
	)
	(wire
		(pts
			(xy 292.1 110.49) (xy 292.1 113.03)
		)
		(stroke
			(width 0)
			(type default)
		)
	)
	(wire
		(pts
			(xy 147.32 140.97) (xy 147.32 146.05)
		)
		(stroke
			(width 0)
			(type default)
		)
	)
	(wire
		(pts
			(xy 172.72 204.47) (xy 175.26 204.47)
		)
		(stroke
			(width 0)
			(type default)
		)
	)
	(wire
		(pts
			(xy 264.16 130.81) (xy 264.16 138.43)
		)
		(stroke
			(width 0)
			(type default)
		)
	)
	(wire
		(pts
			(xy 172.72 179.07) (xy 175.26 179.07)
		)
		(stroke
			(width 0)
			(type default)
		)
	)
	(wire
		(pts
			(xy 175.26 138.43) (xy 175.26 146.05)
		)
		(stroke
			(width 0)
			(type default)
		)
	)
	(wire
		(pts
			(xy 264.16 151.13) (xy 266.7 151.13)
		)
		(stroke
			(width 0)
			(type default)
		)
	)
	(wire
		(pts
			(xy 189.23 125.73) (xy 172.72 125.73)
		)
		(stroke
			(width 0)
			(type default)
		)
	)
	(wire
		(pts
			(xy 147.32 107.95) (xy 149.86 107.95)
		)
		(stroke
			(width 0)
			(type default)
		)
	)
	(wire
		(pts
			(xy 175.26 158.75) (xy 175.26 161.29)
		)
		(stroke
			(width 0)
			(type default)
		)
	)
	(wire
		(pts
			(xy 175.26 130.81) (xy 175.26 138.43)
		)
		(stroke
			(width 0)
			(type default)
		)
	)
	(wire
		(pts
			(xy 289.56 125.73) (xy 292.1 125.73)
		)
		(stroke
			(width 0)
			(type default)
		)
	)
	(wire
		(pts
			(xy 289.56 133.35) (xy 292.1 133.35)
		)
		(stroke
			(width 0)
			(type default)
		)
	)
	(wire
		(pts
			(xy 147.32 102.87) (xy 149.86 102.87)
		)
		(stroke
			(width 0)
			(type default)
		)
	)
	(wire
		(pts
			(xy 147.32 140.97) (xy 149.86 140.97)
		)
		(stroke
			(width 0)
			(type default)
		)
	)
	(wire
		(pts
			(xy 172.72 128.27) (xy 180.34 128.27)
		)
		(stroke
			(width 0)
			(type default)
		)
	)
	(wire
		(pts
			(xy 172.72 151.13) (xy 175.26 151.13)
		)
		(stroke
			(width 0)
			(type default)
		)
	)
	(wire
		(pts
			(xy 172.72 138.43) (xy 175.26 138.43)
		)
		(stroke
			(width 0)
			(type default)
		)
	)
	(wire
		(pts
			(xy 172.72 133.35) (xy 231.14 133.35)
		)
		(stroke
			(width 0)
			(type default)
		)
	)
	(wire
		(pts
			(xy 120.65 93.98) (xy 127 93.98)
		)
		(stroke
			(width 0)
			(type default)
		)
	)
	(wire
		(pts
			(xy 147.32 166.37) (xy 147.32 173.99)
		)
		(stroke
			(width 0)
			(type default)
		)
	)
	(wire
		(pts
			(xy 289.56 209.55) (xy 292.1 209.55)
		)
		(stroke
			(width 0)
			(type default)
		)
	)
	(wire
		(pts
			(xy 264.16 128.27) (xy 266.7 128.27)
		)
		(stroke
			(width 0)
			(type default)
		)
	)
	(wire
		(pts
			(xy 175.26 107.95) (xy 172.72 107.95)
		)
		(stroke
			(width 0)
			(type default)
		)
	)
	(wire
		(pts
			(xy 292.1 163.83) (xy 292.1 166.37)
		)
		(stroke
			(width 0)
			(type default)
		)
	)
	(wire
		(pts
			(xy 264.16 199.39) (xy 264.16 209.55)
		)
		(stroke
			(width 0)
			(type default)
		)
	)
	(wire
		(pts
			(xy 289.56 166.37) (xy 292.1 166.37)
		)
		(stroke
			(width 0)
			(type default)
		)
	)
	(wire
		(pts
			(xy 172.72 196.85) (xy 175.26 196.85)
		)
		(stroke
			(width 0)
			(type default)
		)
	)
	(wire
		(pts
			(xy 264.16 140.97) (xy 264.16 148.59)
		)
		(stroke
			(width 0)
			(type default)
		)
	)
	(wire
		(pts
			(xy 264.16 138.43) (xy 264.16 140.97)
		)
		(stroke
			(width 0)
			(type default)
		)
	)
	(wire
		(pts
			(xy 147.32 146.05) (xy 149.86 146.05)
		)
		(stroke
			(width 0)
			(type default)
		)
	)
	(wire
		(pts
			(xy 147.32 201.93) (xy 149.86 201.93)
		)
		(stroke
			(width 0)
			(type default)
		)
	)
	(wire
		(pts
			(xy 147.32 118.11) (xy 149.86 118.11)
		)
		(stroke
			(width 0)
			(type default)
		)
	)
	(wire
		(pts
			(xy 147.32 201.93) (xy 147.32 208.28)
		)
		(stroke
			(width 0)
			(type default)
		)
	)
	(wire
		(pts
			(xy 147.32 191.77) (xy 149.86 191.77)
		)
		(stroke
			(width 0)
			(type default)
		)
	)
	(wire
		(pts
			(xy 264.16 115.57) (xy 264.16 120.65)
		)
		(stroke
			(width 0)
			(type default)
		)
	)
	(wire
		(pts
			(xy 175.26 151.13) (xy 175.26 158.75)
		)
		(stroke
			(width 0)
			(type default)
		)
	)
	(wire
		(pts
			(xy 149.86 113.03) (xy 92.71 113.03)
		)
		(stroke
			(width 0)
			(type default)
		)
	)
	(wire
		(pts
			(xy 264.16 128.27) (xy 264.16 130.81)
		)
		(stroke
			(width 0)
			(type default)
		)
	)
	(wire
		(pts
			(xy 264.16 209.55) (xy 264.16 210.82)
		)
		(stroke
			(width 0)
			(type default)
		)
	)
	(wire
		(pts
			(xy 289.56 204.47) (xy 292.1 204.47)
		)
		(stroke
			(width 0)
			(type default)
		)
	)
	(wire
		(pts
			(xy 264.16 209.55) (xy 266.7 209.55)
		)
		(stroke
			(width 0)
			(type default)
		)
	)
	(wire
		(pts
			(xy 292.1 166.37) (xy 292.1 173.99)
		)
		(stroke
			(width 0)
			(type default)
		)
	)
	(wire
		(pts
			(xy 175.26 146.05) (xy 175.26 151.13)
		)
		(stroke
			(width 0)
			(type default)
		)
	)
	(wire
		(pts
			(xy 179.07 93.98) (xy 179.07 96.52)
		)
		(stroke
			(width 0)
			(type default)
		)
	)
	(wire
		(pts
			(xy 147.32 110.49) (xy 147.32 118.11)
		)
		(stroke
			(width 0)
			(type default)
		)
	)
	(wire
		(pts
			(xy 264.16 130.81) (xy 266.7 130.81)
		)
		(stroke
			(width 0)
			(type default)
		)
	)
	(wire
		(pts
			(xy 147.32 105.41) (xy 149.86 105.41)
		)
		(stroke
			(width 0)
			(type default)
		)
	)
	(bus
		(pts
			(xy 113.03 74.93) (xy 205.74 74.93)
		)
		(stroke
			(width 0)
			(type default)
		)
	)
	(wire
		(pts
			(xy 172.72 135.89) (xy 231.14 135.89)
		)
		(stroke
			(width 0)
			(type default)
		)
	)
	(wire
		(pts
			(xy 147.32 146.05) (xy 147.32 153.67)
		)
		(stroke
			(width 0)
			(type default)
		)
	)
	(wire
		(pts
			(xy 175.26 93.98) (xy 179.07 93.98)
		)
		(stroke
			(width 0)
			(type default)
		)
	)
	(wire
		(pts
			(xy 147.32 163.83) (xy 147.32 166.37)
		)
		(stroke
			(width 0)
			(type default)
		)
	)
	(wire
		(pts
			(xy 289.56 163.83) (xy 292.1 163.83)
		)
		(stroke
			(width 0)
			(type default)
		)
	)
	(wire
		(pts
			(xy 147.32 105.41) (xy 147.32 107.95)
		)
		(stroke
			(width 0)
			(type default)
		)
	)
	(bus
		(pts
			(xy 91.44 114.3) (xy 91.44 111.76)
		)
		(stroke
			(width 0)
			(type default)
		)
	)
	(wire
		(pts
			(xy 264.16 161.29) (xy 266.7 161.29)
		)
		(stroke
			(width 0)
			(type default)
		)
	)
	(wire
		(pts
			(xy 172.72 110.49) (xy 175.26 110.49)
		)
		(stroke
			(width 0)
			(type default)
		)
	)
	(wire
		(pts
			(xy 120.65 93.98) (xy 120.65 120.65)
		)
		(stroke
			(width 0)
			(type default)
		)
	)
	(wire
		(pts
			(xy 172.72 168.91) (xy 175.26 168.91)
		)
		(stroke
			(width 0)
			(type default)
		)
	)
	(wire
		(pts
			(xy 172.72 186.69) (xy 175.26 186.69)
		)
		(stroke
			(width 0)
			(type default)
		)
	)
	(wire
		(pts
			(xy 264.16 158.75) (xy 266.7 158.75)
		)
		(stroke
			(width 0)
			(type default)
		)
	)
	(wire
		(pts
			(xy 172.72 140.97) (xy 204.47 140.97)
		)
		(stroke
			(width 0)
			(type default)
		)
	)
	(bus
		(pts
			(xy 205.74 175.26) (xy 205.74 172.72)
		)
		(stroke
			(width 0)
			(type default)
		)
	)
	(wire
		(pts
			(xy 175.26 168.91) (xy 175.26 171.45)
		)
		(stroke
			(width 0)
			(type default)
		)
	)
	(wire
		(pts
			(xy 292.1 133.35) (xy 292.1 135.89)
		)
		(stroke
			(width 0)
			(type default)
		)
	)
	(bus
		(pts
			(xy 91.44 109.22) (xy 91.44 111.76)
		)
		(stroke
			(width 0)
			(type default)
		)
	)
	(wire
		(pts
			(xy 175.26 179.07) (xy 175.26 186.69)
		)
		(stroke
			(width 0)
			(type default)
		)
	)
	(wire
		(pts
			(xy 292.1 102.87) (xy 292.1 110.49)
		)
		(stroke
			(width 0)
			(type default)
		)
	)
	(wire
		(pts
			(xy 147.32 102.87) (xy 147.32 105.41)
		)
		(stroke
			(width 0)
			(type default)
		)
	)
	(wire
		(pts
			(xy 175.26 93.98) (xy 175.26 105.41)
		)
		(stroke
			(width 0)
			(type default)
		)
	)
	(wire
		(pts
			(xy 264.16 107.95) (xy 264.16 115.57)
		)
		(stroke
			(width 0)
			(type default)
		)
	)
	(wire
		(pts
			(xy 195.58 119.38) (xy 195.58 116.84)
		)
		(stroke
			(width 0)
			(type default)
		)
	)
	(wire
		(pts
			(xy 179.07 101.6) (xy 179.07 104.14)
		)
		(stroke
			(width 0)
			(type default)
		)
	)
	(wire
		(pts
			(xy 289.56 173.99) (xy 292.1 173.99)
		)
		(stroke
			(width 0)
			(type default)
		)
	)
	(wire
		(pts
			(xy 264.16 120.65) (xy 266.7 120.65)
		)
		(stroke
			(width 0)
			(type default)
		)
	)
	(wire
		(pts
			(xy 292.1 194.31) (xy 292.1 196.85)
		)
		(stroke
			(width 0)
			(type default)
		)
	)
	(wire
		(pts
			(xy 289.56 146.05) (xy 292.1 146.05)
		)
		(stroke
			(width 0)
			(type default)
		)
	)
	(wire
		(pts
			(xy 187.96 93.98) (xy 187.96 96.52)
		)
		(stroke
			(width 0)
			(type default)
		)
	)
	(wire
		(pts
			(xy 120.65 125.73) (xy 125.73 125.73)
		)
		(stroke
			(width 0)
			(type default)
		)
	)
	(wire
		(pts
			(xy 189.23 123.19) (xy 189.23 125.73)
		)
		(stroke
			(width 0)
			(type default)
		)
	)
	(wire
		(pts
			(xy 147.32 189.23) (xy 147.32 191.77)
		)
		(stroke
			(width 0)
			(type default)
		)
	)
	(wire
		(pts
			(xy 149.86 128.27) (xy 142.24 128.27)
		)
		(stroke
			(width 0)
			(type default)
		)
	)
	(wire
		(pts
			(xy 147.32 133.35) (xy 147.32 140.97)
		)
		(stroke
			(width 0)
			(type default)
		)
	)
	(wire
		(pts
			(xy 147.32 199.39) (xy 149.86 199.39)
		)
		(stroke
			(width 0)
			(type default)
		)
	)
	(wire
		(pts
			(xy 292.1 176.53) (xy 292.1 184.15)
		)
		(stroke
			(width 0)
			(type default)
		)
	)
	(wire
		(pts
			(xy 292.1 173.99) (xy 292.1 176.53)
		)
		(stroke
			(width 0)
			(type default)
		)
	)
	(wire
		(pts
			(xy 289.56 194.31) (xy 292.1 194.31)
		)
		(stroke
			(width 0)
			(type default)
		)
	)
	(wire
		(pts
			(xy 264.16 168.91) (xy 264.16 171.45)
		)
		(stroke
			(width 0)
			(type default)
		)
	)
	(bus
		(pts
			(xy 205.74 162.56) (xy 205.74 154.94)
		)
		(stroke
			(width 0)
			(type default)
		)
	)
	(label "PCIe_{x4}.RX2+"
		(at 203.2 163.83 180)
		(effects
			(font
				(size 1.27 1.27)
			)
			(justify right bottom)
		)
	)
	(label "PCIe_{REF0}.CK+"
		(at 229.87 133.35 180)
		(effects
			(font
				(size 1.27 1.27)
			)
			(justify right bottom)
		)
	)
	(label "PCIe_{x4}.TX0-"
		(at 115.57 138.43 0)
		(effects
			(font
				(size 1.27 1.27)
			)
			(justify left bottom)
		)
	)
	(label "PCIe_{REF0}.CK-"
		(at 229.87 135.89 180)
		(effects
			(font
				(size 1.27 1.27)
			)
			(justify right bottom)
		)
	)
	(label "PCIe_{x4}.TX1-"
		(at 115.57 151.13 0)
		(effects
			(font
				(size 1.27 1.27)
			)
			(justify left bottom)
		)
	)
	(label "PCIe_{x4}.TX2+"
		(at 115.57 158.75 0)
		(effects
			(font
				(size 1.27 1.27)
			)
			(justify left bottom)
		)
	)
	(label "3V3_PCIe_AUX"
		(at 132.08 125.73 0)
		(effects
			(font
				(size 1.27 1.27)
			)
			(justify left bottom)
		)
	)
	(label "PCIe_{x4}.TX0+"
		(at 115.57 135.89 0)
		(effects
			(font
				(size 1.27 1.27)
			)
			(justify left bottom)
		)
	)
	(label "PCIe_{x4}.TX1+"
		(at 115.57 148.59 0)
		(effects
			(font
				(size 1.27 1.27)
			)
			(justify left bottom)
		)
	)
	(label "I2C0.SCL"
		(at 93.98 113.03 0)
		(effects
			(font
				(size 1.27 1.27)
			)
			(justify left bottom)
		)
	)
	(label "PCIe_{x4}.RX3+"
		(at 203.2 173.99 180)
		(effects
			(font
				(size 1.27 1.27)
			)
			(justify right bottom)
		)
	)
	(label "PCIe_{x4}.RX0-"
		(at 203.2 143.51 180)
		(effects
			(font
				(size 1.27 1.27)
			)
			(justify right bottom)
		)
	)
	(label "PCIe_{x4}.TX2-"
		(at 115.57 161.29 0)
		(effects
			(font
				(size 1.27 1.27)
			)
			(justify left bottom)
		)
	)
	(label "I2C0.SDA"
		(at 93.98 115.57 0)
		(effects
			(font
				(size 1.27 1.27)
			)
			(justify left bottom)
		)
	)
	(label "PCIe_{x4}.TX3+"
		(at 115.57 168.91 0)
		(effects
			(font
				(size 1.27 1.27)
			)
			(justify left bottom)
		)
	)
	(label "PCIe_{x4}.RX0+"
		(at 203.2 140.97 180)
		(effects
			(font
				(size 1.27 1.27)
			)
			(justify right bottom)
		)
	)
	(label "PCIe_{x4}.RX3-"
		(at 203.2 176.53 180)
		(effects
			(font
				(size 1.27 1.27)
			)
			(justify right bottom)
		)
	)
	(label "PCIe_{x4}.TX3-"
		(at 115.57 171.45 0)
		(effects
			(font
				(size 1.27 1.27)
			)
			(justify left bottom)
		)
	)
	(label "PCIe_{x4}.RX2-"
		(at 203.2 166.37 180)
		(effects
			(font
				(size 1.27 1.27)
			)
			(justify right bottom)
		)
	)
	(label "PCIe_{x4}.RX1-"
		(at 203.2 156.21 180)
		(effects
			(font
				(size 1.27 1.27)
			)
			(justify right bottom)
		)
	)
	(label "PCIe_{x4}.RX1+"
		(at 203.2 153.67 180)
		(effects
			(font
				(size 1.27 1.27)
			)
			(justify right bottom)
		)
	)
	(hierarchical_label "PCIe_{x4}{PCIe}"
		(shape bidirectional)
		(at 105.41 74.93 180)
		(effects
			(font
				(size 1.27 1.27)
			)
			(justify right)
		)
	)
	(hierarchical_label "~{PERST}"
		(shape input)
		(at 180.34 128.27 0)
		(effects
			(font
				(size 1.27 1.27)
			)
			(justify left)
		)
	)
	(hierarchical_label "PCIe_{REF0}{PCIe_{REF}}"
		(shape input)
		(at 236.22 128.27 0)
		(effects
			(font
				(size 1.27 1.27)
			)
			(justify left)
		)
	)
	(hierarchical_label "~{WAKE}"
		(shape output)
		(at 142.24 128.27 180)
		(effects
			(font
				(size 1.27 1.27)
			)
			(justify right)
		)
	)
	(hierarchical_label "I2C0{I2C}"
		(shape bidirectional)
		(at 87.63 107.95 180)
		(effects
			(font
				(size 1.27 1.27)
			)
			(justify right)
		)
	)
	(symbol
		(lib_id "antmicroCapacitorsmisc:C_10u_0805_35V")
		(at 127 96.52 270)
		(unit 1)
		(exclude_from_sim no)
		(in_bom yes)
		(on_board yes)
		(dnp no)
		(fields_autoplaced yes)
		(property "Reference" "C36"
			(at 129.54 97.7963 90)
			(effects
				(font
					(size 1.27 1.27)
					(thickness 0.15)
				)
				(justify left)
			)
		)
		(property "Value" "C_10u_0805_35V"
			(at 116.84 116.84 0)
			(effects
				(font
					(size 1.27 1.27)
					(thickness 0.15)
				)
				(justify left bottom)
				(hide yes)
			)
		)
		(property "Footprint" "antmicro-footprints:C_0805_2012Metric"
			(at 114.3 116.84 0)
			(effects
				(font
					(size 1.27 1.27)
					(thickness 0.15)
				)
				(justify left bottom)
				(hide yes)
			)
		)
		(property "Datasheet" "https://www.murata.com/products/productdetail?partno=GRM21BR6YA106KE43%23"
			(at 111.76 116.84 0)
			(effects
				(font
					(size 1.27 1.27)
					(thickness 0.15)
				)
				(justify left bottom)
				(hide yes)
			)
		)
		(property "Description" "SMD Multilayer Ceramic Capacitor, 10 µF, 35 V, 0805 [2012 Metric], ± 10%, X5R, GRM Series"
			(at 127 96.52 0)
			(effects
				(font
					(size 1.27 1.27)
				)
				(hide yes)
			)
		)
		(property "MPN" "GRM21BR6YA106KE43L"
			(at 109.22 116.84 0)
			(effects
				(font
					(size 1.27 1.27)
					(thickness 0.15)
				)
				(justify left bottom)
				(hide yes)
			)
		)
		(property "Manufacturer" "Murata"
			(at 106.68 116.84 0)
			(effects
				(font
					(size 1.27 1.27)
					(thickness 0.15)
				)
				(justify left bottom)
				(hide yes)
			)
		)
		(property "License" "Apache-2.0"
			(at 104.14 116.84 0)
			(effects
				(font
					(size 1.27 1.27)
					(thickness 0.15)
				)
				(justify left bottom)
				(hide yes)
			)
		)
		(property "Author" "Antmicro"
			(at 101.6 116.84 0)
			(effects
				(font
					(size 1.27 1.27)
					(thickness 0.15)
				)
				(justify left bottom)
				(hide yes)
			)
		)
		(property "Val" "10u"
			(at 129.54 100.3363 90)
			(effects
				(font
					(size 1.27 1.27)
					(thickness 0.15)
				)
				(justify left)
			)
		)
		(property "Voltage" "35V"
			(at 99.06 116.84 0)
			(effects
				(font
					(size 1.27 1.27)
				)
				(justify left bottom)
				(hide yes)
			)
		)
		(property "Dielectric" ""
			(at 96.52 116.84 0)
			(effects
				(font
					(size 1.27 1.27)
				)
				(justify left bottom)
				(hide yes)
			)
		)
		(property "Public" "False"
			(at 93.98 116.84 0)
			(effects
				(font
					(size 1.27 1.27)
				)
				(justify left bottom)
				(hide yes)
			)
		)
		(pin "1"
		)
		(pin "2"
		)
		(instances
			(project "oculink-to-pcie-adapter"
				(path ""
					(reference "C36")
					(unit 1)
				)
			)
		)
	)
	(symbol
		(lib_id "antmicropower:GND")
		(at 147.32 208.28 0)
		(unit 1)
		(exclude_from_sim no)
		(in_bom yes)
		(on_board yes)
		(dnp no)
		(property "Reference" "#PWR07"
			(at 156.21 210.82 0)
			(effects
				(font
					(size 1.27 1.27)
					(thickness 0.15)
				)
				(justify left bottom)
				(hide yes)
			)
		)
		(property "Value" "GND"
			(at 147.32 212.09 0)
			(effects
				(font
					(size 1.27 1.27)
					(thickness 0.15)
				)
			)
		)
		(property "Footprint" ""
			(at 156.21 215.9 0)
			(effects
				(font
					(size 1.27 1.27)
					(thickness 0.15)
				)
				(justify left bottom)
				(hide yes)
			)
		)
		(property "Datasheet" ""
			(at 156.21 220.98 0)
			(effects
				(font
					(size 1.27 1.27)
					(thickness 0.15)
				)
				(justify left bottom)
				(hide yes)
			)
		)
		(property "Description" ""
			(at 147.32 208.28 0)
			(effects
				(font
					(size 1.27 1.27)
				)
				(hide yes)
			)
		)
		(property "Author" "Antmicro"
			(at 156.21 215.9 0)
			(effects
				(font
					(size 1.27 1.27)
					(thickness 0.15)
				)
				(justify left bottom)
				(hide yes)
			)
		)
		(property "License" "Apache-2.0"
			(at 156.21 218.44 0)
			(effects
				(font
					(size 1.27 1.27)
					(thickness 0.15)
				)
				(justify left bottom)
				(hide yes)
			)
		)
		(pin "1"
		)
		(instances
			(project "oculink-to-pcie-adapter"
				(path ""
					(reference "#PWR07")
					(unit 1)
				)
			)
		)
	)
	(symbol
		(lib_id "antmicropower:+12V")
		(at 120.65 91.44 0)
		(unit 1)
		(exclude_from_sim no)
		(in_bom yes)
		(on_board yes)
		(dnp no)
		(property "Reference" "#PWR05"
			(at 120.65 95.25 0)
			(effects
				(font
					(size 1.27 1.27)
				)
				(hide yes)
			)
		)
		(property "Value" "+3V3"
			(at 120.65 87.63 0)
			(effects
				(font
					(size 1.27 1.27)
				)
			)
		)
		(property "Footprint" ""
			(at 120.65 91.44 0)
			(effects
				(font
					(size 1.27 1.27)
				)
				(hide yes)
			)
		)
		(property "Datasheet" ""
			(at 120.65 91.44 0)
			(effects
				(font
					(size 1.27 1.27)
				)
				(hide yes)
			)
		)
		(property "Description" ""
			(at 120.65 91.44 0)
			(effects
				(font
					(size 1.27 1.27)
				)
				(hide yes)
			)
		)
		(pin "1"
		)
		(instances
			(project "oculink-to-pcie-adapter"
				(path ""
					(reference "#PWR05")
					(unit 1)
				)
			)
		)
	)
	(symbol
		(lib_id "antmicroCapacitorsmisc:C_10u_0805_35V")
		(at 195.58 119.38 270)
		(unit 1)
		(exclude_from_sim no)
		(in_bom yes)
		(on_board yes)
		(dnp no)
		(fields_autoplaced yes)
		(property "Reference" "C37"
			(at 198.12 120.6563 90)
			(effects
				(font
					(size 1.27 1.27)
					(thickness 0.15)
				)
				(justify left)
			)
		)
		(property "Value" "C_10u_0805_35V"
			(at 185.42 139.7 0)
			(effects
				(font
					(size 1.27 1.27)
					(thickness 0.15)
				)
				(justify left bottom)
				(hide yes)
			)
		)
		(property "Footprint" "antmicro-footprints:C_0805_2012Metric"
			(at 182.88 139.7 0)
			(effects
				(font
					(size 1.27 1.27)
					(thickness 0.15)
				)
				(justify left bottom)
				(hide yes)
			)
		)
		(property "Datasheet" "https://www.murata.com/products/productdetail?partno=GRM21BR6YA106KE43%23"
			(at 180.34 139.7 0)
			(effects
				(font
					(size 1.27 1.27)
					(thickness 0.15)
				)
				(justify left bottom)
				(hide yes)
			)
		)
		(property "Description" "SMD Multilayer Ceramic Capacitor, 10 µF, 35 V, 0805 [2012 Metric], ± 10%, X5R, GRM Series"
			(at 195.58 119.38 0)
			(effects
				(font
					(size 1.27 1.27)
				)
				(hide yes)
			)
		)
		(property "MPN" "GRM21BR6YA106KE43L"
			(at 177.8 139.7 0)
			(effects
				(font
					(size 1.27 1.27)
					(thickness 0.15)
				)
				(justify left bottom)
				(hide yes)
			)
		)
		(property "Manufacturer" "Murata"
			(at 175.26 139.7 0)
			(effects
				(font
					(size 1.27 1.27)
					(thickness 0.15)
				)
				(justify left bottom)
				(hide yes)
			)
		)
		(property "License" "Apache-2.0"
			(at 172.72 139.7 0)
			(effects
				(font
					(size 1.27 1.27)
					(thickness 0.15)
				)
				(justify left bottom)
				(hide yes)
			)
		)
		(property "Author" "Antmicro"
			(at 170.18 139.7 0)
			(effects
				(font
					(size 1.27 1.27)
					(thickness 0.15)
				)
				(justify left bottom)
				(hide yes)
			)
		)
		(property "Val" "10u"
			(at 198.12 123.1963 90)
			(effects
				(font
					(size 1.27 1.27)
					(thickness 0.15)
				)
				(justify left)
			)
		)
		(property "Voltage" "35V"
			(at 167.64 139.7 0)
			(effects
				(font
					(size 1.27 1.27)
				)
				(justify left bottom)
				(hide yes)
			)
		)
		(property "Dielectric" ""
			(at 165.1 139.7 0)
			(effects
				(font
					(size 1.27 1.27)
				)
				(justify left bottom)
				(hide yes)
			)
		)
		(property "Public" "False"
			(at 162.56 139.7 0)
			(effects
				(font
					(size 1.27 1.27)
				)
				(justify left bottom)
				(hide yes)
			)
		)
		(pin "1"
		)
		(pin "2"
		)
		(instances
			(project "oculink-to-pcie-adapter"
				(path ""
					(reference "C37")
					(unit 1)
				)
			)
		)
	)
	(symbol
		(lib_id "antmicropower:GND")
		(at 187.96 104.14 0)
		(mirror y)
		(unit 1)
		(exclude_from_sim no)
		(in_bom yes)
		(on_board yes)
		(dnp no)
		(property "Reference" "#PWR099"
			(at 179.07 106.68 0)
			(effects
				(font
					(size 1.27 1.27)
					(thickness 0.15)
				)
				(justify left bottom)
				(hide yes)
			)
		)
		(property "Value" "GND"
			(at 187.96 107.95 0)
			(effects
				(font
					(size 1.27 1.27)
					(thickness 0.15)
				)
			)
		)
		(property "Footprint" ""
			(at 179.07 111.76 0)
			(effects
				(font
					(size 1.27 1.27)
					(thickness 0.15)
				)
				(justify left bottom)
				(hide yes)
			)
		)
		(property "Datasheet" ""
			(at 179.07 116.84 0)
			(effects
				(font
					(size 1.27 1.27)
					(thickness 0.15)
				)
				(justify left bottom)
				(hide yes)
			)
		)
		(property "Description" ""
			(at 187.96 104.14 0)
			(effects
				(font
					(size 1.27 1.27)
				)
				(hide yes)
			)
		)
		(property "Author" "Antmicro"
			(at 179.07 111.76 0)
			(effects
				(font
					(size 1.27 1.27)
					(thickness 0.15)
				)
				(justify left bottom)
				(hide yes)
			)
		)
		(property "License" "Apache-2.0"
			(at 179.07 114.3 0)
			(effects
				(font
					(size 1.27 1.27)
					(thickness 0.15)
				)
				(justify left bottom)
				(hide yes)
			)
		)
		(pin "1"
		)
		(instances
			(project "oculink-to-pcie-adapter"
				(path ""
					(reference "#PWR099")
					(unit 1)
				)
			)
		)
	)
	(symbol
		(lib_id "antmicroTVSDiodes:SZSMF4L14AT3G")
		(at 187.96 96.52 90)
		(mirror x)
		(unit 1)
		(exclude_from_sim no)
		(in_bom yes)
		(on_board yes)
		(dnp no)
		(property "Reference" "D9"
			(at 189.484 97.79 90)
			(effects
				(font
					(size 1.27 1.27)
					(thickness 0.15)
				)
				(justify right)
			)
		)
		(property "Value" "SZSMF4L14AT3G"
			(at 198.12 111.76 0)
			(effects
				(font
					(size 1.27 1.27)
					(thickness 0.15)
				)
				(justify left bottom)
				(hide yes)
			)
		)
		(property "Footprint" "antmicro-footprints:SOD-123FL"
			(at 200.66 111.76 0)
			(effects
				(font
					(size 1.27 1.27)
					(thickness 0.15)
				)
				(justify left bottom)
				(hide yes)
			)
		)
		(property "Datasheet" "https://www.mouser.com/datasheet/2/240/media-3320461.pdf"
			(at 203.2 111.76 0)
			(effects
				(font
					(size 1.27 1.27)
					(thickness 0.15)
				)
				(justify left bottom)
				(hide yes)
			)
		)
		(property "Description" "ESD, TVS Diode, 14V, UNI, 400W, SOD-123FL"
			(at 187.96 96.52 0)
			(effects
				(font
					(size 1.27 1.27)
				)
				(hide yes)
			)
		)
		(property "MPN" "SZSMF4L12AT3G"
			(at 189.484 100.33 90)
			(effects
				(font
					(size 1.27 1.27)
					(thickness 0.15)
				)
				(justify right)
			)
		)
		(property "Author" "Antmicro"
			(at 205.74 111.76 0)
			(effects
				(font
					(size 1.27 1.27)
					(thickness 0.15)
				)
				(justify left bottom)
				(hide yes)
			)
		)
		(property "License" "Apache-2.0"
			(at 208.28 111.76 0)
			(effects
				(font
					(size 1.27 1.27)
					(thickness 0.15)
				)
				(justify left bottom)
				(hide yes)
			)
		)
		(property "Manufacturer" "Littelfuse"
			(at 210.82 111.76 0)
			(effects
				(font
					(size 1.27 1.27)
					(thickness 0.15)
				)
				(justify left bottom)
				(hide yes)
			)
		)
		(pin "1"
		)
		(pin "2"
		)
		(instances
			(project "oculink-to-pcie-adapter"
				(path ""
					(reference "D9")
					(unit 1)
				)
			)
		)
	)
	(symbol
		(lib_id "antmicroPciConnectors:PCIe_x16_10146070-113Y0LF-vertical")
		(at 149.86 102.87 0)
		(unit 1)
		(exclude_from_sim no)
		(in_bom yes)
		(on_board yes)
		(dnp no)
		(fields_autoplaced yes)
		(property "Reference" "J2"
			(at 161.29 95.25 0)
			(effects
				(font
					(size 1.27 1.27)
					(thickness 0.15)
				)
			)
		)
		(property "Value" "PCIe_x16_10146070-113Y0LF-vertical"
			(at 185.42 107.95 0)
			(effects
				(font
					(size 1.27 1.27)
					(thickness 0.15)
				)
				(justify left bottom)
				(hide yes)
			)
		)
		(property "Footprint" "antmicro-footprints:AMPHENOL_10146070-113Y0LF"
			(at 185.42 110.49 0)
			(effects
				(font
					(size 1.27 1.27)
					(thickness 0.15)
				)
				(justify left bottom)
				(hide yes)
			)
		)
		(property "Datasheet" "https://www.farnell.com/datasheets/3212936.pdf"
			(at 185.42 113.03 0)
			(effects
				(font
					(size 1.27 1.27)
					(thickness 0.15)
				)
				(justify left bottom)
				(hide yes)
			)
		)
		(property "Description" "164 Position Female Connector PCI Express™ Gold 0.039\" (1.00mm) Black"
			(at 149.86 102.87 0)
			(effects
				(font
					(size 1.27 1.27)
				)
				(hide yes)
			)
		)
		(property "PARTREV" "E"
			(at 185.42 115.57 0)
			(effects
				(font
					(size 1.27 1.27)
					(thickness 0.15)
				)
				(justify left bottom)
				(hide yes)
			)
		)
		(property "STANDARD" "Manufacturer Recommendations"
			(at 185.42 118.11 0)
			(effects
				(font
					(size 1.27 1.27)
					(thickness 0.15)
				)
				(justify left bottom)
				(hide yes)
			)
		)
		(property "MAXIMUM_PACKAGE_HEIGHT" "11.25mm"
			(at 185.42 120.65 0)
			(effects
				(font
					(size 1.27 1.27)
					(thickness 0.15)
				)
				(justify left bottom)
				(hide yes)
			)
		)
		(property "Manufacturer" "Amphenol"
			(at 185.42 123.19 0)
			(effects
				(font
					(size 1.27 1.27)
					(thickness 0.15)
				)
				(justify left bottom)
				(hide yes)
			)
		)
		(property "Author" "Antmicro"
			(at 185.42 125.73 0)
			(effects
				(font
					(size 1.27 1.27)
					(thickness 0.15)
				)
				(justify left bottom)
				(hide yes)
			)
		)
		(property "License" "Apache-2.0"
			(at 185.42 128.27 0)
			(effects
				(font
					(size 1.27 1.27)
					(thickness 0.15)
				)
				(justify left bottom)
				(hide yes)
			)
		)
		(property "MPN" "10146070-113Y0LF"
			(at 161.29 97.79 0)
			(effects
				(font
					(size 1.27 1.27)
					(thickness 0.15)
				)
			)
		)
		(pin "B63"
		)
		(pin "A16"
		)
		(pin "B49"
		)
		(pin "B55"
		)
		(pin "B79"
		)
		(pin "A12"
		)
		(pin "A26"
		)
		(pin "A40"
		)
		(pin "A4"
		)
		(pin "A47"
		)
		(pin "A22"
		)
		(pin "B81"
		)
		(pin "B15"
		)
		(pin "B4"
		)
		(pin "A38"
		)
		(pin "B3"
		)
		(pin "B80"
		)
		(pin "B8"
		)
		(pin "A56"
		)
		(pin "A43"
		)
		(pin "B30"
		)
		(pin "B27"
		)
		(pin "A65"
		)
		(pin "B76"
		)
		(pin "B46"
		)
		(pin "A69"
		)
		(pin "A32"
		)
		(pin "A77"
		)
		(pin "A42"
		)
		(pin "B51"
		)
		(pin "A58"
		)
		(pin "B48"
		)
		(pin "A30"
		)
		(pin "A15"
		)
		(pin "B22"
		)
		(pin "B45"
		)
		(pin "A6"
		)
		(pin "B38"
		)
		(pin "A73"
		)
		(pin "B70"
		)
		(pin "B28"
		)
		(pin "A24"
		)
		(pin "B25"
		)
		(pin "A64"
		)
		(pin "B23"
		)
		(pin "B72"
		)
		(pin "B56"
		)
		(pin "A49"
		)
		(pin "A46"
		)
		(pin "B39"
		)
		(pin "A59"
		)
		(pin "A9"
		)
		(pin "A72"
		)
		(pin "B47"
		)
		(pin "A74"
		)
		(pin "B54"
		)
		(pin "A81"
		)
		(pin "B66"
		)
		(pin "B43"
		)
		(pin "A50"
		)
		(pin "A17"
		)
		(pin "A34"
		)
		(pin "A33"
		)
		(pin "B32"
		)
		(pin "B61"
		)
		(pin "B50"
		)
		(pin "A2"
		)
		(pin "A62"
		)
		(pin "B58"
		)
		(pin "B40"
		)
		(pin "A44"
		)
		(pin "B35"
		)
		(pin "B18"
		)
		(pin "B59"
		)
		(pin "B13"
		)
		(pin "B19"
		)
		(pin "A39"
		)
		(pin "B68"
		)
		(pin "B16"
		)
		(pin "B24"
		)
		(pin "B60"
		)
		(pin "A60"
		)
		(pin "B78"
		)
		(pin "B65"
		)
		(pin "A78"
		)
		(pin "A31"
		)
		(pin "A79"
		)
		(pin "B82"
		)
		(pin "B12"
		)
		(pin "A75"
		)
		(pin "B71"
		)
		(pin "B69"
		)
		(pin "B57"
		)
		(pin "A36"
		)
		(pin "A52"
		)
		(pin "B73"
		)
		(pin "B21"
		)
		(pin "A63"
		)
		(pin "A67"
		)
		(pin "A5"
		)
		(pin "B29"
		)
		(pin "B74"
		)
		(pin "B11"
		)
		(pin "A19"
		)
		(pin "A68"
		)
		(pin "S1"
		)
		(pin "B41"
		)
		(pin "A8"
		)
		(pin "B64"
		)
		(pin "A18"
		)
		(pin "A71"
		)
		(pin "A70"
		)
		(pin "B33"
		)
		(pin "A82"
		)
		(pin "B20"
		)
		(pin "B14"
		)
		(pin "A10"
		)
		(pin "B75"
		)
		(pin "B53"
		)
		(pin "A25"
		)
		(pin "B17"
		)
		(pin "B52"
		)
		(pin "B9"
		)
		(pin "B31"
		)
		(pin "B37"
		)
		(pin "B26"
		)
		(pin "A37"
		)
		(pin "A80"
		)
		(pin "A35"
		)
		(pin "B10"
		)
		(pin "A57"
		)
		(pin "A55"
		)
		(pin "A61"
		)
		(pin "S2"
		)
		(pin "B62"
		)
		(pin "B67"
		)
		(pin "A45"
		)
		(pin "A66"
		)
		(pin "A76"
		)
		(pin "A1"
		)
		(pin "B1"
		)
		(pin "A3"
		)
		(pin "A54"
		)
		(pin "A41"
		)
		(pin "A27"
		)
		(pin "B44"
		)
		(pin "A28"
		)
		(pin "A7"
		)
		(pin "A29"
		)
		(pin "B34"
		)
		(pin "A20"
		)
		(pin "A13"
		)
		(pin "A53"
		)
		(pin "A48"
		)
		(pin "A11"
		)
		(pin "A23"
		)
		(pin "B77"
		)
		(pin "B36"
		)
		(pin "A51"
		)
		(pin "A21"
		)
		(pin "B5"
		)
		(pin "B6"
		)
		(pin "B7"
		)
		(pin "B42"
		)
		(pin "A14"
		)
		(pin "B2"
		)
		(instances
			(project ""
				(path ""
					(reference "J2")
					(unit 1)
				)
			)
		)
	)
	(symbol
		(lib_id "antmicropower:GND")
		(at 127 104.14 0)
		(unit 1)
		(exclude_from_sim no)
		(in_bom yes)
		(on_board yes)
		(dnp no)
		(property "Reference" "#PWR087"
			(at 135.89 106.68 0)
			(effects
				(font
					(size 1.27 1.27)
					(thickness 0.15)
				)
				(justify left bottom)
				(hide yes)
			)
		)
		(property "Value" "GND"
			(at 127 107.95 0)
			(effects
				(font
					(size 1.27 1.27)
					(thickness 0.15)
				)
			)
		)
		(property "Footprint" ""
			(at 135.89 111.76 0)
			(effects
				(font
					(size 1.27 1.27)
					(thickness 0.15)
				)
				(justify left bottom)
				(hide yes)
			)
		)
		(property "Datasheet" ""
			(at 135.89 116.84 0)
			(effects
				(font
					(size 1.27 1.27)
					(thickness 0.15)
				)
				(justify left bottom)
				(hide yes)
			)
		)
		(property "Description" ""
			(at 127 104.14 0)
			(effects
				(font
					(size 1.27 1.27)
				)
				(hide yes)
			)
		)
		(property "Author" "Antmicro"
			(at 135.89 111.76 0)
			(effects
				(font
					(size 1.27 1.27)
					(thickness 0.15)
				)
				(justify left bottom)
				(hide yes)
			)
		)
		(property "License" "Apache-2.0"
			(at 135.89 114.3 0)
			(effects
				(font
					(size 1.27 1.27)
					(thickness 0.15)
				)
				(justify left bottom)
				(hide yes)
			)
		)
		(pin "1"
		)
		(instances
			(project "oculink-to-pcie-adapter"
				(path ""
					(reference "#PWR087")
					(unit 1)
				)
			)
		)
	)
	(symbol
		(lib_id "antmicropower:+12V_AON")
		(at 147.32 91.44 0)
		(unit 1)
		(exclude_from_sim no)
		(in_bom yes)
		(on_board yes)
		(dnp no)
		(property "Reference" "#PWR06"
			(at 147.32 95.25 0)
			(effects
				(font
					(size 1.27 1.27)
				)
				(hide yes)
			)
		)
		(property "Value" "+12V"
			(at 147.32 87.63 0)
			(effects
				(font
					(size 1.27 1.27)
				)
			)
		)
		(property "Footprint" ""
			(at 147.32 91.44 0)
			(effects
				(font
					(size 1.27 1.27)
				)
				(hide yes)
			)
		)
		(property "Datasheet" ""
			(at 147.32 91.44 0)
			(effects
				(font
					(size 1.27 1.27)
				)
				(hide yes)
			)
		)
		(property "Description" ""
			(at 147.32 91.44 0)
			(effects
				(font
					(size 1.27 1.27)
				)
				(hide yes)
			)
		)
		(pin "1"
		)
		(instances
			(project "oculink-to-pcie-adapter"
				(path ""
					(reference "#PWR06")
					(unit 1)
				)
			)
		)
	)
	(symbol
		(lib_id "antmicropower:GND")
		(at 292.1 210.82 0)
		(unit 1)
		(exclude_from_sim no)
		(in_bom yes)
		(on_board yes)
		(dnp no)
		(property "Reference" "#PWR010"
			(at 292.1 217.17 0)
			(effects
				(font
					(size 1.27 1.27)
				)
				(hide yes)
			)
		)
		(property "Value" "GND"
			(at 292.1 214.63 0)
			(effects
				(font
					(size 1.27 1.27)
				)
			)
		)
		(property "Footprint" ""
			(at 292.1 210.82 0)
			(effects
				(font
					(size 1.27 1.27)
				)
				(hide yes)
			)
		)
		(property "Datasheet" ""
			(at 292.1 210.82 0)
			(effects
				(font
					(size 1.27 1.27)
				)
				(hide yes)
			)
		)
		(property "Description" ""
			(at 292.1 210.82 0)
			(effects
				(font
					(size 1.27 1.27)
				)
				(hide yes)
			)
		)
		(property "Author" "Antmicro"
			(at 300.99 218.44 0)
			(effects
				(font
					(size 1.27 1.27)
					(thickness 0.15)
				)
				(justify left bottom)
				(hide yes)
			)
		)
		(property "License" "Apache-2.0"
			(at 300.99 220.98 0)
			(effects
				(font
					(size 1.27 1.27)
					(thickness 0.15)
				)
				(justify left bottom)
				(hide yes)
			)
		)
		(pin "1"
		)
		(instances
			(project "oculink-to-pcie-adapter"
				(path ""
					(reference "#PWR010")
					(unit 1)
				)
			)
		)
	)
	(symbol
		(lib_id "antmicropower:GND")
		(at 195.58 127 0)
		(unit 1)
		(exclude_from_sim no)
		(in_bom yes)
		(on_board yes)
		(dnp no)
		(property "Reference" "#PWR088"
			(at 204.47 129.54 0)
			(effects
				(font
					(size 1.27 1.27)
					(thickness 0.15)
				)
				(justify left bottom)
				(hide yes)
			)
		)
		(property "Value" "GND"
			(at 195.58 130.81 0)
			(effects
				(font
					(size 1.27 1.27)
					(thickness 0.15)
				)
			)
		)
		(property "Footprint" ""
			(at 204.47 134.62 0)
			(effects
				(font
					(size 1.27 1.27)
					(thickness 0.15)
				)
				(justify left bottom)
				(hide yes)
			)
		)
		(property "Datasheet" ""
			(at 204.47 139.7 0)
			(effects
				(font
					(size 1.27 1.27)
					(thickness 0.15)
				)
				(justify left bottom)
				(hide yes)
			)
		)
		(property "Description" ""
			(at 195.58 127 0)
			(effects
				(font
					(size 1.27 1.27)
				)
				(hide yes)
			)
		)
		(property "Author" "Antmicro"
			(at 204.47 134.62 0)
			(effects
				(font
					(size 1.27 1.27)
					(thickness 0.15)
				)
				(justify left bottom)
				(hide yes)
			)
		)
		(property "License" "Apache-2.0"
			(at 204.47 137.16 0)
			(effects
				(font
					(size 1.27 1.27)
					(thickness 0.15)
				)
				(justify left bottom)
				(hide yes)
			)
		)
		(pin "1"
		)
		(instances
			(project "oculink-to-pcie-adapter"
				(path ""
					(reference "#PWR088")
					(unit 1)
				)
			)
		)
	)
	(symbol
		(lib_id "antmicropower:GND")
		(at 179.07 104.14 0)
		(unit 1)
		(exclude_from_sim no)
		(in_bom yes)
		(on_board yes)
		(dnp no)
		(property "Reference" "#PWR035"
			(at 187.96 106.68 0)
			(effects
				(font
					(size 1.27 1.27)
					(thickness 0.15)
				)
				(justify left bottom)
				(hide yes)
			)
		)
		(property "Value" "GND"
			(at 179.07 107.95 0)
			(effects
				(font
					(size 1.27 1.27)
					(thickness 0.15)
				)
			)
		)
		(property "Footprint" ""
			(at 187.96 111.76 0)
			(effects
				(font
					(size 1.27 1.27)
					(thickness 0.15)
				)
				(justify left bottom)
				(hide yes)
			)
		)
		(property "Datasheet" ""
			(at 187.96 116.84 0)
			(effects
				(font
					(size 1.27 1.27)
					(thickness 0.15)
				)
				(justify left bottom)
				(hide yes)
			)
		)
		(property "Description" ""
			(at 179.07 104.14 0)
			(effects
				(font
					(size 1.27 1.27)
				)
				(hide yes)
			)
		)
		(property "Author" "Antmicro"
			(at 187.96 111.76 0)
			(effects
				(font
					(size 1.27 1.27)
					(thickness 0.15)
				)
				(justify left bottom)
				(hide yes)
			)
		)
		(property "License" "Apache-2.0"
			(at 187.96 114.3 0)
			(effects
				(font
					(size 1.27 1.27)
					(thickness 0.15)
				)
				(justify left bottom)
				(hide yes)
			)
		)
		(pin "1"
		)
		(instances
			(project "oculink-to-pcie-adapter"
				(path ""
					(reference "#PWR035")
					(unit 1)
				)
			)
		)
	)
	(symbol
		(lib_id "antmicropower:GND")
		(at 138.43 104.14 0)
		(unit 1)
		(exclude_from_sim no)
		(in_bom yes)
		(on_board yes)
		(dnp no)
		(property "Reference" "#PWR034"
			(at 147.32 106.68 0)
			(effects
				(font
					(size 1.27 1.27)
					(thickness 0.15)
				)
				(justify left bottom)
				(hide yes)
			)
		)
		(property "Value" "GND"
			(at 138.43 107.95 0)
			(effects
				(font
					(size 1.27 1.27)
					(thickness 0.15)
				)
			)
		)
		(property "Footprint" ""
			(at 147.32 111.76 0)
			(effects
				(font
					(size 1.27 1.27)
					(thickness 0.15)
				)
				(justify left bottom)
				(hide yes)
			)
		)
		(property "Datasheet" ""
			(at 147.32 116.84 0)
			(effects
				(font
					(size 1.27 1.27)
					(thickness 0.15)
				)
				(justify left bottom)
				(hide yes)
			)
		)
		(property "Description" ""
			(at 138.43 104.14 0)
			(effects
				(font
					(size 1.27 1.27)
				)
				(hide yes)
			)
		)
		(property "Author" "Antmicro"
			(at 147.32 111.76 0)
			(effects
				(font
					(size 1.27 1.27)
					(thickness 0.15)
				)
				(justify left bottom)
				(hide yes)
			)
		)
		(property "License" "Apache-2.0"
			(at 147.32 114.3 0)
			(effects
				(font
					(size 1.27 1.27)
					(thickness 0.15)
				)
				(justify left bottom)
				(hide yes)
			)
		)
		(pin "1"
		)
		(instances
			(project "oculink-to-pcie-adapter"
				(path ""
					(reference "#PWR034")
					(unit 1)
				)
			)
		)
	)
	(symbol
		(lib_id "antmicropower:+12V_AON")
		(at 175.26 91.44 0)
		(unit 1)
		(exclude_from_sim no)
		(in_bom yes)
		(on_board yes)
		(dnp no)
		(property "Reference" "#PWR03"
			(at 175.26 95.25 0)
			(effects
				(font
					(size 1.27 1.27)
				)
				(hide yes)
			)
		)
		(property "Value" "+12V"
			(at 175.26 87.63 0)
			(effects
				(font
					(size 1.27 1.27)
				)
			)
		)
		(property "Footprint" ""
			(at 175.26 91.44 0)
			(effects
				(font
					(size 1.27 1.27)
				)
				(hide yes)
			)
		)
		(property "Datasheet" ""
			(at 175.26 91.44 0)
			(effects
				(font
					(size 1.27 1.27)
				)
				(hide yes)
			)
		)
		(property "Description" ""
			(at 175.26 91.44 0)
			(effects
				(font
					(size 1.27 1.27)
				)
				(hide yes)
			)
		)
		(pin "1"
		)
		(instances
			(project "oculink-to-pcie-adapter"
				(path ""
					(reference "#PWR03")
					(unit 1)
				)
			)
		)
	)
	(symbol
		(lib_id "antmicroCapacitorsmisc:C_10u_0805_35V")
		(at 179.07 96.52 270)
		(unit 1)
		(exclude_from_sim no)
		(in_bom yes)
		(on_board yes)
		(dnp no)
		(fields_autoplaced yes)
		(property "Reference" "C8"
			(at 181.61 97.7963 90)
			(effects
				(font
					(size 1.27 1.27)
					(thickness 0.15)
				)
				(justify left)
			)
		)
		(property "Value" "C_10u_0805_35V"
			(at 168.91 116.84 0)
			(effects
				(font
					(size 1.27 1.27)
					(thickness 0.15)
				)
				(justify left bottom)
				(hide yes)
			)
		)
		(property "Footprint" "antmicro-footprints:C_0805_2012Metric"
			(at 166.37 116.84 0)
			(effects
				(font
					(size 1.27 1.27)
					(thickness 0.15)
				)
				(justify left bottom)
				(hide yes)
			)
		)
		(property "Datasheet" "https://www.murata.com/products/productdetail?partno=GRM21BR6YA106KE43%23"
			(at 163.83 116.84 0)
			(effects
				(font
					(size 1.27 1.27)
					(thickness 0.15)
				)
				(justify left bottom)
				(hide yes)
			)
		)
		(property "Description" "SMD Multilayer Ceramic Capacitor, 10 µF, 35 V, 0805 [2012 Metric], ± 10%, X5R, GRM Series"
			(at 179.07 96.52 0)
			(effects
				(font
					(size 1.27 1.27)
				)
				(hide yes)
			)
		)
		(property "MPN" "GRM21BR6YA106KE43L"
			(at 161.29 116.84 0)
			(effects
				(font
					(size 1.27 1.27)
					(thickness 0.15)
				)
				(justify left bottom)
				(hide yes)
			)
		)
		(property "Manufacturer" "Murata"
			(at 158.75 116.84 0)
			(effects
				(font
					(size 1.27 1.27)
					(thickness 0.15)
				)
				(justify left bottom)
				(hide yes)
			)
		)
		(property "License" "Apache-2.0"
			(at 156.21 116.84 0)
			(effects
				(font
					(size 1.27 1.27)
					(thickness 0.15)
				)
				(justify left bottom)
				(hide yes)
			)
		)
		(property "Author" "Antmicro"
			(at 153.67 116.84 0)
			(effects
				(font
					(size 1.27 1.27)
					(thickness 0.15)
				)
				(justify left bottom)
				(hide yes)
			)
		)
		(property "Val" "10u"
			(at 181.61 100.3363 90)
			(effects
				(font
					(size 1.27 1.27)
					(thickness 0.15)
				)
				(justify left)
			)
		)
		(property "Voltage" "35V"
			(at 151.13 116.84 0)
			(effects
				(font
					(size 1.27 1.27)
				)
				(justify left bottom)
				(hide yes)
			)
		)
		(property "Dielectric" ""
			(at 148.59 116.84 0)
			(effects
				(font
					(size 1.27 1.27)
				)
				(justify left bottom)
				(hide yes)
			)
		)
		(property "Public" "False"
			(at 146.05 116.84 0)
			(effects
				(font
					(size 1.27 1.27)
				)
				(justify left bottom)
				(hide yes)
			)
		)
		(pin "1"
		)
		(pin "2"
		)
		(instances
			(project "oculink-to-pcie-adapter"
				(path ""
					(reference "C8")
					(unit 1)
				)
			)
		)
	)
	(symbol
		(lib_id "antmicroResistors0402:R_0R_0402")
		(at 125.73 125.73 0)
		(unit 1)
		(exclude_from_sim no)
		(in_bom yes)
		(on_board yes)
		(dnp no)
		(property "Reference" "R3"
			(at 128.27 123.698 0)
			(effects
				(font
					(size 1.27 1.27)
					(thickness 0.15)
				)
			)
		)
		(property "Value" "R_0R_0402"
			(at 146.05 138.43 0)
			(effects
				(font
					(size 1.27 1.27)
					(thickness 0.15)
				)
				(justify left bottom)
				(hide yes)
			)
		)
		(property "Footprint" "antmicro-footprints:R_0402_1005Metric"
			(at 146.05 140.97 0)
			(effects
				(font
					(size 1.27 1.27)
					(thickness 0.15)
				)
				(justify left bottom)
				(hide yes)
			)
		)
		(property "Datasheet" "https://industrial.panasonic.com/cdbs/www-data/pdf/RDA0000/AOA0000C301.pdf"
			(at 146.05 143.51 0)
			(effects
				(font
					(size 1.27 1.27)
					(thickness 0.15)
				)
				(justify left bottom)
				(hide yes)
			)
		)
		(property "Description" "SMD Chip Resistor, Jumper, 0 ohm, 100 mW, 0402 [1005 Metric], Thick Film, General Purpose"
			(at 125.73 125.73 0)
			(effects
				(font
					(size 1.27 1.27)
				)
				(hide yes)
			)
		)
		(property "MPN" "ERJ2GE0R00X"
			(at 146.05 146.05 0)
			(effects
				(font
					(size 1.27 1.27)
					(thickness 0.15)
				)
				(justify left bottom)
				(hide yes)
			)
		)
		(property "Manufacturer" "Panasonic"
			(at 146.05 148.59 0)
			(effects
				(font
					(size 1.27 1.27)
					(thickness 0.15)
				)
				(justify left bottom)
				(hide yes)
			)
		)
		(property "License" "Apache-2.0"
			(at 146.05 151.13 0)
			(effects
				(font
					(size 1.27 1.27)
					(thickness 0.15)
				)
				(justify left bottom)
				(hide yes)
			)
		)
		(property "Author" "Antmicro"
			(at 146.05 153.67 0)
			(effects
				(font
					(size 1.27 1.27)
					(thickness 0.15)
				)
				(justify left bottom)
				(hide yes)
			)
		)
		(property "Val" "0R"
			(at 128.27 127.762 0)
			(effects
				(font
					(size 1.27 1.27)
					(thickness 0.15)
				)
			)
		)
		(property "Tolerance" "~"
			(at 146.05 135.89 0)
			(effects
				(font
					(size 1.27 1.27)
				)
				(justify left bottom)
				(hide yes)
			)
		)
		(property "Current" "1A"
			(at 146.05 156.21 0)
			(effects
				(font
					(size 1.27 1.27)
					(thickness 0.15)
				)
				(justify left bottom)
				(hide yes)
			)
		)
		(pin "1"
		)
		(pin "2"
		)
		(instances
			(project ""
				(path ""
					(reference "R3")
					(unit 1)
				)
			)
		)
	)
	(symbol
		(lib_id "antmicroCapacitorsmisc:C_10u_0805_35V")
		(at 138.43 96.52 270)
		(unit 1)
		(exclude_from_sim no)
		(in_bom yes)
		(on_board yes)
		(dnp no)
		(fields_autoplaced yes)
		(property "Reference" "C6"
			(at 140.97 97.7963 90)
			(effects
				(font
					(size 1.27 1.27)
					(thickness 0.15)
				)
				(justify left)
			)
		)
		(property "Value" "C_10u_0805_35V"
			(at 128.27 116.84 0)
			(effects
				(font
					(size 1.27 1.27)
					(thickness 0.15)
				)
				(justify left bottom)
				(hide yes)
			)
		)
		(property "Footprint" "antmicro-footprints:C_0805_2012Metric"
			(at 125.73 116.84 0)
			(effects
				(font
					(size 1.27 1.27)
					(thickness 0.15)
				)
				(justify left bottom)
				(hide yes)
			)
		)
		(property "Datasheet" "https://www.murata.com/products/productdetail?partno=GRM21BR6YA106KE43%23"
			(at 123.19 116.84 0)
			(effects
				(font
					(size 1.27 1.27)
					(thickness 0.15)
				)
				(justify left bottom)
				(hide yes)
			)
		)
		(property "Description" "SMD Multilayer Ceramic Capacitor, 10 µF, 35 V, 0805 [2012 Metric], ± 10%, X5R, GRM Series"
			(at 138.43 96.52 0)
			(effects
				(font
					(size 1.27 1.27)
				)
				(hide yes)
			)
		)
		(property "MPN" "GRM21BR6YA106KE43L"
			(at 120.65 116.84 0)
			(effects
				(font
					(size 1.27 1.27)
					(thickness 0.15)
				)
				(justify left bottom)
				(hide yes)
			)
		)
		(property "Manufacturer" "Murata"
			(at 118.11 116.84 0)
			(effects
				(font
					(size 1.27 1.27)
					(thickness 0.15)
				)
				(justify left bottom)
				(hide yes)
			)
		)
		(property "License" "Apache-2.0"
			(at 115.57 116.84 0)
			(effects
				(font
					(size 1.27 1.27)
					(thickness 0.15)
				)
				(justify left bottom)
				(hide yes)
			)
		)
		(property "Author" "Antmicro"
			(at 113.03 116.84 0)
			(effects
				(font
					(size 1.27 1.27)
					(thickness 0.15)
				)
				(justify left bottom)
				(hide yes)
			)
		)
		(property "Val" "10u"
			(at 140.97 100.3363 90)
			(effects
				(font
					(size 1.27 1.27)
					(thickness 0.15)
				)
				(justify left)
			)
		)
		(property "Voltage" "35V"
			(at 110.49 116.84 0)
			(effects
				(font
					(size 1.27 1.27)
				)
				(justify left bottom)
				(hide yes)
			)
		)
		(property "Dielectric" ""
			(at 107.95 116.84 0)
			(effects
				(font
					(size 1.27 1.27)
				)
				(justify left bottom)
				(hide yes)
			)
		)
		(property "Public" "False"
			(at 105.41 116.84 0)
			(effects
				(font
					(size 1.27 1.27)
				)
				(justify left bottom)
				(hide yes)
			)
		)
		(pin "1"
		)
		(pin "2"
		)
		(instances
			(project ""
				(path ""
					(reference "C6")
					(unit 1)
				)
			)
		)
	)
	(symbol
		(lib_id "antmicropower:GND")
		(at 175.26 208.28 0)
		(unit 1)
		(exclude_from_sim no)
		(in_bom yes)
		(on_board yes)
		(dnp no)
		(property "Reference" "#PWR08"
			(at 175.26 214.63 0)
			(effects
				(font
					(size 1.27 1.27)
				)
				(hide yes)
			)
		)
		(property "Value" "GND"
			(at 175.26 212.09 0)
			(effects
				(font
					(size 1.27 1.27)
				)
			)
		)
		(property "Footprint" ""
			(at 175.26 208.28 0)
			(effects
				(font
					(size 1.27 1.27)
				)
				(hide yes)
			)
		)
		(property "Datasheet" ""
			(at 175.26 208.28 0)
			(effects
				(font
					(size 1.27 1.27)
				)
				(hide yes)
			)
		)
		(property "Description" ""
			(at 175.26 208.28 0)
			(effects
				(font
					(size 1.27 1.27)
				)
				(hide yes)
			)
		)
		(property "Author" "Antmicro"
			(at 184.15 215.9 0)
			(effects
				(font
					(size 1.27 1.27)
					(thickness 0.15)
				)
				(justify left bottom)
				(hide yes)
			)
		)
		(property "License" "Apache-2.0"
			(at 184.15 218.44 0)
			(effects
				(font
					(size 1.27 1.27)
					(thickness 0.15)
				)
				(justify left bottom)
				(hide yes)
			)
		)
		(pin "1"
		)
		(instances
			(project "oculink-to-pcie-adapter"
				(path ""
					(reference "#PWR08")
					(unit 1)
				)
			)
		)
	)
	(symbol
		(lib_id "antmicropower:+12V")
		(at 189.23 114.3 0)
		(unit 1)
		(exclude_from_sim no)
		(in_bom yes)
		(on_board yes)
		(dnp no)
		(property "Reference" "#PWR04"
			(at 189.23 118.11 0)
			(effects
				(font
					(size 1.27 1.27)
				)
				(hide yes)
			)
		)
		(property "Value" "+3V3"
			(at 189.23 110.49 0)
			(effects
				(font
					(size 1.27 1.27)
				)
			)
		)
		(property "Footprint" ""
			(at 189.23 114.3 0)
			(effects
				(font
					(size 1.27 1.27)
				)
				(hide yes)
			)
		)
		(property "Datasheet" ""
			(at 189.23 114.3 0)
			(effects
				(font
					(size 1.27 1.27)
				)
				(hide yes)
			)
		)
		(property "Description" ""
			(at 189.23 114.3 0)
			(effects
				(font
					(size 1.27 1.27)
				)
				(hide yes)
			)
		)
		(pin "1"
		)
		(instances
			(project "oculink-to-pcie-adapter"
				(path ""
					(reference "#PWR04")
					(unit 1)
				)
			)
		)
	)
	(symbol
		(lib_id "antmicroPciConnectors:PCIe_x16_10146070-113Y0LF-vertical")
		(at 266.7 102.87 0)
		(unit 2)
		(exclude_from_sim no)
		(in_bom yes)
		(on_board yes)
		(dnp no)
		(fields_autoplaced yes)
		(property "Reference" "J2"
			(at 278.13 95.25 0)
			(effects
				(font
					(size 1.27 1.27)
					(thickness 0.15)
				)
			)
		)
		(property "Value" "PCIe_x16_10146070-113Y0LF-vertical"
			(at 302.26 107.95 0)
			(effects
				(font
					(size 1.27 1.27)
					(thickness 0.15)
				)
				(justify left bottom)
				(hide yes)
			)
		)
		(property "Footprint" "antmicro-footprints:AMPHENOL_10146070-113Y0LF"
			(at 302.26 110.49 0)
			(effects
				(font
					(size 1.27 1.27)
					(thickness 0.15)
				)
				(justify left bottom)
				(hide yes)
			)
		)
		(property "Datasheet" "https://www.farnell.com/datasheets/3212936.pdf"
			(at 302.26 113.03 0)
			(effects
				(font
					(size 1.27 1.27)
					(thickness 0.15)
				)
				(justify left bottom)
				(hide yes)
			)
		)
		(property "Description" "164 Position Female Connector PCI Express™ Gold 0.039\" (1.00mm) Black"
			(at 266.7 102.87 0)
			(effects
				(font
					(size 1.27 1.27)
				)
				(hide yes)
			)
		)
		(property "PARTREV" "E"
			(at 302.26 115.57 0)
			(effects
				(font
					(size 1.27 1.27)
					(thickness 0.15)
				)
				(justify left bottom)
				(hide yes)
			)
		)
		(property "STANDARD" "Manufacturer Recommendations"
			(at 302.26 118.11 0)
			(effects
				(font
					(size 1.27 1.27)
					(thickness 0.15)
				)
				(justify left bottom)
				(hide yes)
			)
		)
		(property "MAXIMUM_PACKAGE_HEIGHT" "11.25mm"
			(at 302.26 120.65 0)
			(effects
				(font
					(size 1.27 1.27)
					(thickness 0.15)
				)
				(justify left bottom)
				(hide yes)
			)
		)
		(property "Manufacturer" "Amphenol"
			(at 302.26 123.19 0)
			(effects
				(font
					(size 1.27 1.27)
					(thickness 0.15)
				)
				(justify left bottom)
				(hide yes)
			)
		)
		(property "Author" "Antmicro"
			(at 302.26 125.73 0)
			(effects
				(font
					(size 1.27 1.27)
					(thickness 0.15)
				)
				(justify left bottom)
				(hide yes)
			)
		)
		(property "License" "Apache-2.0"
			(at 302.26 128.27 0)
			(effects
				(font
					(size 1.27 1.27)
					(thickness 0.15)
				)
				(justify left bottom)
				(hide yes)
			)
		)
		(property "MPN" "10146070-113Y0LF"
			(at 278.13 97.79 0)
			(effects
				(font
					(size 1.27 1.27)
					(thickness 0.15)
				)
			)
		)
		(pin "B63"
		)
		(pin "A16"
		)
		(pin "B49"
		)
		(pin "B55"
		)
		(pin "B79"
		)
		(pin "A12"
		)
		(pin "A26"
		)
		(pin "A40"
		)
		(pin "A4"
		)
		(pin "A47"
		)
		(pin "A22"
		)
		(pin "B81"
		)
		(pin "B15"
		)
		(pin "B4"
		)
		(pin "A38"
		)
		(pin "B3"
		)
		(pin "B80"
		)
		(pin "B8"
		)
		(pin "A56"
		)
		(pin "A43"
		)
		(pin "B30"
		)
		(pin "B27"
		)
		(pin "A65"
		)
		(pin "B76"
		)
		(pin "B46"
		)
		(pin "A69"
		)
		(pin "A32"
		)
		(pin "A77"
		)
		(pin "A42"
		)
		(pin "B51"
		)
		(pin "A58"
		)
		(pin "B48"
		)
		(pin "A30"
		)
		(pin "A15"
		)
		(pin "B22"
		)
		(pin "B45"
		)
		(pin "A6"
		)
		(pin "B38"
		)
		(pin "A73"
		)
		(pin "B70"
		)
		(pin "B28"
		)
		(pin "A24"
		)
		(pin "B25"
		)
		(pin "A64"
		)
		(pin "B23"
		)
		(pin "B72"
		)
		(pin "B56"
		)
		(pin "A49"
		)
		(pin "A46"
		)
		(pin "B39"
		)
		(pin "A59"
		)
		(pin "A9"
		)
		(pin "A72"
		)
		(pin "B47"
		)
		(pin "A74"
		)
		(pin "B54"
		)
		(pin "A81"
		)
		(pin "B66"
		)
		(pin "B43"
		)
		(pin "A50"
		)
		(pin "A17"
		)
		(pin "A34"
		)
		(pin "A33"
		)
		(pin "B32"
		)
		(pin "B61"
		)
		(pin "B50"
		)
		(pin "A2"
		)
		(pin "A62"
		)
		(pin "B58"
		)
		(pin "B40"
		)
		(pin "A44"
		)
		(pin "B35"
		)
		(pin "B18"
		)
		(pin "B59"
		)
		(pin "B13"
		)
		(pin "B19"
		)
		(pin "A39"
		)
		(pin "B68"
		)
		(pin "B16"
		)
		(pin "B24"
		)
		(pin "B60"
		)
		(pin "A60"
		)
		(pin "B78"
		)
		(pin "B65"
		)
		(pin "A78"
		)
		(pin "A31"
		)
		(pin "A79"
		)
		(pin "B82"
		)
		(pin "B12"
		)
		(pin "A75"
		)
		(pin "B71"
		)
		(pin "B69"
		)
		(pin "B57"
		)
		(pin "A36"
		)
		(pin "A52"
		)
		(pin "B73"
		)
		(pin "B21"
		)
		(pin "A63"
		)
		(pin "A67"
		)
		(pin "A5"
		)
		(pin "B29"
		)
		(pin "B74"
		)
		(pin "B11"
		)
		(pin "A19"
		)
		(pin "A68"
		)
		(pin "S1"
		)
		(pin "B41"
		)
		(pin "A8"
		)
		(pin "B64"
		)
		(pin "A18"
		)
		(pin "A71"
		)
		(pin "A70"
		)
		(pin "B33"
		)
		(pin "A82"
		)
		(pin "B20"
		)
		(pin "B14"
		)
		(pin "A10"
		)
		(pin "B75"
		)
		(pin "B53"
		)
		(pin "A25"
		)
		(pin "B17"
		)
		(pin "B52"
		)
		(pin "B9"
		)
		(pin "B31"
		)
		(pin "B37"
		)
		(pin "B26"
		)
		(pin "A37"
		)
		(pin "A80"
		)
		(pin "A35"
		)
		(pin "B10"
		)
		(pin "A57"
		)
		(pin "A55"
		)
		(pin "A61"
		)
		(pin "S2"
		)
		(pin "B62"
		)
		(pin "B67"
		)
		(pin "A45"
		)
		(pin "A66"
		)
		(pin "A76"
		)
		(pin "A1"
		)
		(pin "B1"
		)
		(pin "A3"
		)
		(pin "A54"
		)
		(pin "A41"
		)
		(pin "A27"
		)
		(pin "B44"
		)
		(pin "A28"
		)
		(pin "A7"
		)
		(pin "A29"
		)
		(pin "B34"
		)
		(pin "A20"
		)
		(pin "A13"
		)
		(pin "A53"
		)
		(pin "A48"
		)
		(pin "A11"
		)
		(pin "A23"
		)
		(pin "B77"
		)
		(pin "B36"
		)
		(pin "A51"
		)
		(pin "A21"
		)
		(pin "B5"
		)
		(pin "B6"
		)
		(pin "B7"
		)
		(pin "B42"
		)
		(pin "A14"
		)
		(pin "B2"
		)
		(instances
			(project ""
				(path ""
					(reference "J2")
					(unit 2)
				)
			)
		)
	)
	(symbol
		(lib_id "antmicropower:GND")
		(at 264.16 210.82 0)
		(unit 1)
		(exclude_from_sim no)
		(in_bom yes)
		(on_board yes)
		(dnp no)
		(property "Reference" "#PWR09"
			(at 264.16 217.17 0)
			(effects
				(font
					(size 1.27 1.27)
				)
				(hide yes)
			)
		)
		(property "Value" "GND"
			(at 264.16 214.63 0)
			(effects
				(font
					(size 1.27 1.27)
				)
			)
		)
		(property "Footprint" ""
			(at 264.16 210.82 0)
			(effects
				(font
					(size 1.27 1.27)
				)
				(hide yes)
			)
		)
		(property "Datasheet" ""
			(at 264.16 210.82 0)
			(effects
				(font
					(size 1.27 1.27)
				)
				(hide yes)
			)
		)
		(property "Description" ""
			(at 264.16 210.82 0)
			(effects
				(font
					(size 1.27 1.27)
				)
				(hide yes)
			)
		)
		(property "Author" "Antmicro"
			(at 273.05 218.44 0)
			(effects
				(font
					(size 1.27 1.27)
					(thickness 0.15)
				)
				(justify left bottom)
				(hide yes)
			)
		)
		(property "License" "Apache-2.0"
			(at 273.05 220.98 0)
			(effects
				(font
					(size 1.27 1.27)
					(thickness 0.15)
				)
				(justify left bottom)
				(hide yes)
			)
		)
		(pin "1"
		)
		(instances
			(project "oculink-to-pcie-adapter"
				(path ""
					(reference "#PWR09")
					(unit 1)
				)
			)
		)
	)
)
